FILE_TYPE = MACRO_DRAWING;
SET COLOR_WIRE YELLOW;
SET COLOR_PROP ORANGE;
SET COLOR_DOT WHITE;
SET COLOR_ARC YELLOW;
SET COLOR_BODY GREEN;
SET COLOR_NOTE PURPLE;
SET PROP_DISPLAY VALUE;
SET PAGE_NUMBER P245;
FORCEADD GND..1
(-3300 -1475);
FORCEPROP 3 LASTPIN (-3300 -1425) SIG_NAME GND\g
J 0
(-3290 -1415);
DISPLAY 0.659574 (-3290 -1415);
PAINT MONO (-3290 -1415);
DISPLAY INVISIBLE (-3290 -1415);
FORCEPROP 2 LAST CDS_LIB pure_quanta_power
J 0
(-3300 -1475);
DISPLAY INVISIBLE (-3300 -1475);
FORCEPROP 1 LAST SIZE 1B
J 0
(-3225 -1525);
DISPLAY 0.872340 (-3225 -1525);
PAINT AQUA (-3225 -1525);
DISPLAY INVISIBLE (-3225 -1525);
FORCEPROP 1 LAST HDL_POWER GND
J 0
(-3300 -1325);
DISPLAY 0.872340 (-3300 -1325);
PAINT GREEN (-3300 -1325);
DISPLAY INVISIBLE (-3300 -1325);
FORCEPROP 1 LAST PATH I1
J 0
(-3225 -1475);
DISPLAY 0.872340 (-3225 -1475);
PAINT AQUA (-3225 -1475);
DISPLAY INVISIBLE (-3225 -1475);
FORCEADD Q_RES..2
(-2150 -975);
FORCEPROP 1 LAST LOCATION PR832
J 0
(-2105 -850);
DISPLAY 0.617021 (-2105 -850);
PAINT AQUA (-2105 -850);
FORCEPROP 0 LAST $SEC 1
J 0
(-2100 -800);
DISPLAY 0.680851 (-2100 -800);
PAINT MONO (-2100 -800);
DISPLAY INVISIBLE (-2100 -800);
FORCEPROP 0 LAST CDS_SEC 1
J 0
(-2100 -800);
DISPLAY 1.021277 (-2100 -800);
DISPLAY INVISIBLE (-2100 -800);
FORCEPROP 1 LASTPIN (-2150 -875) $PN 1
J 0
(-2145 -913);
DISPLAY 0.617021 (-2145 -913);
PAINT MONO (-2145 -913);
FORCEPROP 1 LASTPIN (-2150 -1075) $PN 2
J 0
(-2145 -1065);
DISPLAY 0.617021 (-2145 -1065);
PAINT MONO (-2145 -1065);
FORCEPROP 1 LAST PACK_TYPE 0402LF
J 0
(-2110 -1150);
DISPLAY 0.617021 (-2110 -1150);
PAINT SKYBLUE (-2110 -1150);
FORCEPROP 1 LAST VALUE 0
J 0
(-2105 -900);
DISPLAY 0.617021 (-2105 -900);
PAINT SKYBLUE (-2105 -900);
FORCEPROP 1 LAST TOLERANCE 5%
J 0
(-2105 -950);
DISPLAY 0.617021 (-2105 -950);
PAINT SKYBLUE (-2105 -950);
FORCEPROP 1 LAST MATERIAL CHIP
J 0
(-2110 -1050);
DISPLAY 0.617021 (-2110 -1050);
PAINT SKYBLUE (-2110 -1050);
FORCEPROP 1 LAST WATTAGE 1/16W
J 0
(-2110 -1000);
DISPLAY 0.617021 (-2110 -1000);
PAINT SKYBLUE (-2110 -1000);
FORCEPROP 2 LAST CDS_LIB pure_quanta
J 0
(-2150 -975);
DISPLAY INVISIBLE (-2150 -975);
FORCEPROP 1 LAST PATH I10
J 0
(-2100 -800);
DISPLAY 0.978723 (-2100 -800);
PAINT WHITE (-2100 -800);
DISPLAY INVISIBLE (-2100 -800);
FORCEPROP 1 LAST PART_NUMBER CS00002JB13
J 0
(-2110 -1100);
DISPLAY 0.617021 (-2110 -1100);
PAINT BLUE (-2110 -1100);
DISPLAY INVISIBLE (-2110 -1100);
FORCEADD Q_RES..2
(-2800 -600);
FORCEPROP 1 LAST LOCATION R1571
J 0
(-2750 -475);
DISPLAY 0.638298 (-2750 -475);
FORCEPROP 0 LAST $SEC 1
J 0
(-2750 -425);
DISPLAY 0.680851 (-2750 -425);
PAINT MONO (-2750 -425);
DISPLAY INVISIBLE (-2750 -425);
FORCEPROP 0 LAST CDS_SEC 1
J 0
(-2750 -425);
DISPLAY 1.021277 (-2750 -425);
DISPLAY INVISIBLE (-2750 -425);
FORCEPROP 1 LASTPIN (-2800 -500) $PN 1
J 0
(-2795 -538);
DISPLAY 0.787234 (-2795 -538);
PAINT MONO (-2795 -538);
FORCEPROP 1 LASTPIN (-2800 -700) $PN 2
J 0
(-2795 -690);
DISPLAY 0.787234 (-2795 -690);
PAINT MONO (-2795 -690);
FORCEPROP 1 LAST PACK_TYPE 0402LF
J 0
(-2760 -775);
DISPLAY 0.638298 (-2760 -775);
FORCEPROP 1 LAST MATERIAL CHIP
J 0
(-2760 -675);
DISPLAY 0.638298 (-2760 -675);
FORCEPROP 1 LAST WATTAGE 1/16W
J 0
(-2760 -625);
DISPLAY 0.638298 (-2760 -625);
FORCEPROP 1 LAST TOLERANCE 5%
J 0
(-2755 -575);
DISPLAY 0.638298 (-2755 -575);
FORCEPROP 1 LAST VALUE 0
J 0
(-2755 -525);
DISPLAY 0.638298 (-2755 -525);
FORCEPROP 2 LAST CDS_LIB pure_quanta
J 0
(-2800 -600);
DISPLAY INVISIBLE (-2800 -600);
FORCEPROP 1 LAST PATH I11
J 0
(-2750 -425);
DISPLAY 0.978723 (-2750 -425);
PAINT WHITE (-2750 -425);
DISPLAY INVISIBLE (-2750 -425);
FORCEPROP 1 LAST PART_NUMBER CS00002JB13
J 0
(-2760 -725);
DISPLAY 0.638298 (-2760 -725);
DISPLAY INVISIBLE (-2760 -725);
FORCEPROP 1 LAST LOCATION R1571
J 0
(-2850 -500);
DISPLAY 1.021277 (-2850 -500);
PAINT AQUA (-2850 -500);
DISPLAY INVISIBLE (-2850 -500);
FORCEADD Q_CAP..1
(-2050 -375);
FORCEPROP 1 LAST LOCATION PC581
J 0
(-2000 -275);
DISPLAY 0.617021 (-2000 -275);
PAINT AQUA (-2000 -275);
FORCEPROP 0 LAST $SEC 1
J 0
(-2000 -225);
DISPLAY 0.680851 (-2000 -225);
PAINT MONO (-2000 -225);
DISPLAY INVISIBLE (-2000 -225);
FORCEPROP 0 LAST CDS_SEC 1
J 0
(-2000 -225);
DISPLAY 1.021277 (-2000 -225);
DISPLAY INVISIBLE (-2000 -225);
FORCEPROP 1 LASTPIN (-2050 -275) $PN 1
J 0
(-2040 -295);
DISPLAY 0.617021 (-2040 -295);
PAINT MONO (-2040 -295);
FORCEPROP 1 LASTPIN (-2050 -475) $PN 2
J 0
(-2040 -495);
DISPLAY 0.617021 (-2040 -495);
PAINT MONO (-2040 -495);
FORCEPROP 1 LAST PACK_TYPE C0603
J 0
(-2000 -575);
DISPLAY 0.617021 (-2000 -575);
PAINT SKYBLUE (-2000 -575);
FORCEPROP 1 LAST VOLTAGE 16V
J 0
(-2000 -375);
DISPLAY 0.617021 (-2000 -375);
PAINT SKYBLUE (-2000 -375);
FORCEPROP 1 LAST VALUE 4.7UF
J 0
(-2000 -325);
DISPLAY 0.617021 (-2000 -325);
PAINT SKYBLUE (-2000 -325);
FORCEPROP 1 LAST MATERIAL X6S
J 0
(-2000 -475);
DISPLAY 0.617021 (-2000 -475);
PAINT SKYBLUE (-2000 -475);
FORCEPROP 1 LAST TOLERANCE 10%
J 0
(-2000 -425);
DISPLAY 0.617021 (-2000 -425);
PAINT SKYBLUE (-2000 -425);
FORCEPROP 2 LAST CDS_LIB pure_quanta
J 0
(-2050 -375);
DISPLAY INVISIBLE (-2050 -375);
FORCEPROP 1 LAST PATH I12
J 0
(-2000 -225);
DISPLAY 0.978723 (-2000 -225);
PAINT WHITE (-2000 -225);
DISPLAY INVISIBLE (-2000 -225);
FORCEPROP 1 LAST PART_NUMBER CH5473KE902
J 0
(-2000 -525);
DISPLAY 0.617021 (-2000 -525);
PAINT BLUE (-2000 -525);
DISPLAY INVISIBLE (-2000 -525);
FORCEADD GND..1
(-2050 -600);
FORCEPROP 3 LASTPIN (-2050 -550) SIG_NAME GND\g
J 0
(-2040 -540);
DISPLAY 0.659574 (-2040 -540);
PAINT MONO (-2040 -540);
DISPLAY INVISIBLE (-2040 -540);
FORCEPROP 1 LAST SIZE 1B
J 0
(-1975 -650);
DISPLAY 0.872340 (-1975 -650);
PAINT AQUA (-1975 -650);
DISPLAY INVISIBLE (-1975 -650);
FORCEPROP 2 LAST CDS_LIB pure_quanta_power
J 0
(-2050 -600);
DISPLAY INVISIBLE (-2050 -600);
FORCEPROP 1 LAST HDL_POWER GND
J 0
(-2050 -450);
DISPLAY 0.872340 (-2050 -450);
PAINT GREEN (-2050 -450);
DISPLAY INVISIBLE (-2050 -450);
FORCEPROP 1 LAST PATH I13
J 0
(-1975 -600);
DISPLAY 0.872340 (-1975 -600);
PAINT AQUA (-1975 -600);
DISPLAY INVISIBLE (-1975 -600);
FORCEADD GND..1
(-1750 -1275);
FORCEPROP 3 LASTPIN (-1750 -1225) SIG_NAME GND\g
J 0
(-1740 -1215);
DISPLAY 0.659574 (-1740 -1215);
PAINT MONO (-1740 -1215);
DISPLAY INVISIBLE (-1740 -1215);
FORCEPROP 2 LAST CDS_LIB pure_quanta_power
J 0
(-1750 -1275);
DISPLAY INVISIBLE (-1750 -1275);
FORCEPROP 1 LAST SIZE 1B
J 0
(-1675 -1325);
DISPLAY 0.872340 (-1675 -1325);
PAINT AQUA (-1675 -1325);
DISPLAY INVISIBLE (-1675 -1325);
FORCEPROP 1 LAST HDL_POWER GND
J 0
(-1750 -1125);
DISPLAY 0.872340 (-1750 -1125);
PAINT GREEN (-1750 -1125);
DISPLAY INVISIBLE (-1750 -1125);
FORCEPROP 1 LAST PATH I14
J 0
(-1675 -1275);
DISPLAY 0.872340 (-1675 -1275);
PAINT AQUA (-1675 -1275);
DISPLAY INVISIBLE (-1675 -1275);
FORCEADD Q_RES..2
(-1750 -1075);
FORCEPROP 1 LAST LOCATION PR833
J 0
(-1705 -950);
DISPLAY 0.617021 (-1705 -950);
PAINT AQUA (-1705 -950);
FORCEPROP 0 LAST $SEC 1
J 0
(-1700 -900);
DISPLAY 0.680851 (-1700 -900);
PAINT MONO (-1700 -900);
DISPLAY INVISIBLE (-1700 -900);
FORCEPROP 0 LAST CDS_SEC 1
J 0
(-1700 -900);
DISPLAY 1.021277 (-1700 -900);
DISPLAY INVISIBLE (-1700 -900);
FORCEPROP 1 LASTPIN (-1750 -975) $PN 1
J 0
(-1745 -1013);
DISPLAY 0.617021 (-1745 -1013);
PAINT MONO (-1745 -1013);
FORCEPROP 1 LASTPIN (-1750 -1175) $PN 2
J 0
(-1745 -1165);
DISPLAY 0.617021 (-1745 -1165);
PAINT MONO (-1745 -1165);
FORCEPROP 1 LAST TOLERANCE 1%
J 0
(-1705 -1050);
DISPLAY 0.617021 (-1705 -1050);
PAINT SKYBLUE (-1705 -1050);
FORCEPROP 1 LAST PACK_TYPE 0402LF
J 0
(-1710 -1250);
DISPLAY 0.617021 (-1710 -1250);
PAINT SKYBLUE (-1710 -1250);
FORCEPROP 1 LAST VALUE 1.5K
J 0
(-1705 -1000);
DISPLAY 0.617021 (-1705 -1000);
PAINT SKYBLUE (-1705 -1000);
FORCEPROP 1 LAST MATERIAL EMPTY
J 0
(-1710 -1150);
DISPLAY 0.617021 (-1710 -1150);
PAINT RED (-1710 -1150);
FORCEPROP 1 LAST WATTAGE 1/16W
J 0
(-1710 -1100);
DISPLAY 0.617021 (-1710 -1100);
PAINT SKYBLUE (-1710 -1100);
FORCEPROP 2 LAST CDS_LIB pure_quanta
J 0
(-1750 -1075);
DISPLAY INVISIBLE (-1750 -1075);
FORCEPROP 1 LAST PATH I15
J 0
(-1700 -900);
DISPLAY 0.978723 (-1700 -900);
PAINT WHITE (-1700 -900);
DISPLAY INVISIBLE (-1700 -900);
FORCEPROP 1 LAST PART_NUMBER CS21502FB07
J 0
(-1725 -1200);
DISPLAY 0.617021 (-1725 -1200);
PAINT BLUE (-1725 -1200);
DISPLAY INVISIBLE (-1725 -1200);
FORCEADD GND..1
(-1350 -1375);
FORCEPROP 3 LASTPIN (-1350 -1325) SIG_NAME GND\g
J 0
(-1340 -1315);
DISPLAY 0.659574 (-1340 -1315);
PAINT MONO (-1340 -1315);
DISPLAY INVISIBLE (-1340 -1315);
FORCEPROP 1 LAST SIZE 1B
J 0
(-1275 -1425);
DISPLAY 0.872340 (-1275 -1425);
PAINT AQUA (-1275 -1425);
DISPLAY INVISIBLE (-1275 -1425);
FORCEPROP 2 LAST CDS_LIB pure_quanta_power
J 0
(-1350 -1375);
DISPLAY INVISIBLE (-1350 -1375);
FORCEPROP 1 LAST HDL_POWER GND
J 0
(-1350 -1225);
DISPLAY 0.872340 (-1350 -1225);
PAINT GREEN (-1350 -1225);
DISPLAY INVISIBLE (-1350 -1225);
FORCEPROP 1 LAST PATH I16
J 0
(-1275 -1375);
DISPLAY 0.872340 (-1275 -1375);
PAINT AQUA (-1275 -1375);
DISPLAY INVISIBLE (-1275 -1375);
FORCEADD Q_RES..2
(-1350 -1175);
FORCEPROP 1 LAST LOCATION PR834
J 0
(-1300 -1050);
DISPLAY 0.617021 (-1300 -1050);
PAINT AQUA (-1300 -1050);
FORCEPROP 0 LAST $SEC 1
J 0
(-1300 -1000);
DISPLAY 0.680851 (-1300 -1000);
PAINT MONO (-1300 -1000);
DISPLAY INVISIBLE (-1300 -1000);
FORCEPROP 0 LAST CDS_SEC 1
J 0
(-1300 -1000);
DISPLAY 1.021277 (-1300 -1000);
DISPLAY INVISIBLE (-1300 -1000);
FORCEPROP 1 LASTPIN (-1350 -1075) $PN 1
J 0
(-1345 -1113);
DISPLAY 0.617021 (-1345 -1113);
PAINT MONO (-1345 -1113);
FORCEPROP 1 LASTPIN (-1350 -1275) $PN 2
J 0
(-1345 -1265);
DISPLAY 0.617021 (-1345 -1265);
PAINT MONO (-1345 -1265);
FORCEPROP 1 LAST WATTAGE 1/16W
J 0
(-1305 -1200);
DISPLAY 0.617021 (-1305 -1200);
PAINT SKYBLUE (-1305 -1200);
FORCEPROP 1 LAST TOLERANCE 1%
J 0
(-1300 -1150);
DISPLAY 0.617021 (-1300 -1150);
PAINT SKYBLUE (-1300 -1150);
FORCEPROP 1 LAST PACK_TYPE 0402LF
J 0
(-1300 -1350);
DISPLAY 0.617021 (-1300 -1350);
PAINT SKYBLUE (-1300 -1350);
FORCEPROP 1 LAST MATERIAL CHIP
J 0
(-1305 -1250);
DISPLAY 0.617021 (-1305 -1250);
PAINT SKYBLUE (-1305 -1250);
FORCEPROP 1 LAST VALUE 21.5K
J 0
(-1300 -1100);
DISPLAY 0.617021 (-1300 -1100);
PAINT SKYBLUE (-1300 -1100);
FORCEPROP 2 LAST CDS_LIB pure_quanta
J 0
(-1350 -1175);
DISPLAY INVISIBLE (-1350 -1175);
FORCEPROP 1 LAST PATH I17
J 0
(-1300 -1000);
DISPLAY 0.978723 (-1300 -1000);
PAINT WHITE (-1300 -1000);
DISPLAY INVISIBLE (-1300 -1000);
FORCEPROP 1 LAST PART_NUMBER CS32152FB04
J 0
(-1305 -1300);
DISPLAY 0.617021 (-1305 -1300);
PAINT BLUE (-1305 -1300);
DISPLAY INVISIBLE (-1305 -1300);
FORCEADD GND..1
(-1625 -600);
FORCEPROP 3 LASTPIN (-1625 -550) SIG_NAME GND\g
J 0
(-1615 -540);
DISPLAY 0.659574 (-1615 -540);
PAINT MONO (-1615 -540);
DISPLAY INVISIBLE (-1615 -540);
FORCEPROP 2 LAST CDS_LIB pure_quanta_power
J 0
(-1625 -600);
DISPLAY INVISIBLE (-1625 -600);
FORCEPROP 1 LAST SIZE 1B
J 0
(-1550 -650);
DISPLAY 0.872340 (-1550 -650);
PAINT AQUA (-1550 -650);
DISPLAY INVISIBLE (-1550 -650);
FORCEPROP 1 LAST HDL_POWER GND
J 0
(-1625 -450);
DISPLAY 0.872340 (-1625 -450);
PAINT GREEN (-1625 -450);
DISPLAY INVISIBLE (-1625 -450);
FORCEPROP 1 LAST PATH I18
J 0
(-1550 -600);
DISPLAY 0.872340 (-1550 -600);
PAINT AQUA (-1550 -600);
DISPLAY INVISIBLE (-1550 -600);
FORCEADD Q_CAP..1
(-1625 -375);
FORCEPROP 1 LAST LOCATION PC591
J 0
(-1575 -275);
DISPLAY 0.617021 (-1575 -275);
PAINT AQUA (-1575 -275);
FORCEPROP 0 LAST $SEC 1
J 0
(-1575 -225);
DISPLAY 0.680851 (-1575 -225);
PAINT MONO (-1575 -225);
DISPLAY INVISIBLE (-1575 -225);
FORCEPROP 0 LAST CDS_SEC 1
J 0
(-1575 -225);
DISPLAY 1.021277 (-1575 -225);
DISPLAY INVISIBLE (-1575 -225);
FORCEPROP 1 LASTPIN (-1625 -275) $PN 1
J 0
(-1615 -295);
DISPLAY 0.617021 (-1615 -295);
PAINT MONO (-1615 -295);
FORCEPROP 1 LASTPIN (-1625 -475) $PN 2
J 0
(-1615 -495);
DISPLAY 0.617021 (-1615 -495);
PAINT MONO (-1615 -495);
FORCEPROP 1 LAST PACK_TYPE C0603
J 0
(-1575 -575);
DISPLAY 0.617021 (-1575 -575);
PAINT SKYBLUE (-1575 -575);
FORCEPROP 1 LAST VALUE 2.2UF
J 0
(-1575 -325);
DISPLAY 0.617021 (-1575 -325);
PAINT SKYBLUE (-1575 -325);
FORCEPROP 1 LAST VOLTAGE 16V
J 0
(-1575 -375);
DISPLAY 0.617021 (-1575 -375);
PAINT SKYBLUE (-1575 -375);
FORCEPROP 1 LAST TOLERANCE 10%
J 0
(-1575 -425);
DISPLAY 0.617021 (-1575 -425);
PAINT SKYBLUE (-1575 -425);
FORCEPROP 1 LAST MATERIAL X6S
J 0
(-1575 -475);
DISPLAY 0.617021 (-1575 -475);
PAINT SKYBLUE (-1575 -475);
FORCEPROP 2 LAST CDS_LIB pure_quanta
J 0
(-1625 -375);
DISPLAY INVISIBLE (-1625 -375);
FORCEPROP 1 LAST PATH I19
J 0
(-1575 -225);
DISPLAY 0.978723 (-1575 -225);
PAINT WHITE (-1575 -225);
DISPLAY INVISIBLE (-1575 -225);
FORCEPROP 1 LAST PART_NUMBER CH5223KE901
J 0
(-1575 -525);
DISPLAY 0.617021 (-1575 -525);
PAINT BLUE (-1575 -525);
DISPLAY INVISIBLE (-1575 -525);
FORCEADD Q_RES..2
(-3300 -1175);
FORCEPROP 1 LAST LOCATION R3118
J 0
(-3255 -1050);
DISPLAY 0.787234 (-3255 -1050);
FORCEPROP 0 LAST $SEC 1
J 0
(-3250 -1000);
DISPLAY 0.680851 (-3250 -1000);
PAINT MONO (-3250 -1000);
DISPLAY INVISIBLE (-3250 -1000);
FORCEPROP 0 LAST CDS_SEC 1
J 0
(-3250 -1000);
DISPLAY 1.021277 (-3250 -1000);
DISPLAY INVISIBLE (-3250 -1000);
FORCEPROP 1 LASTPIN (-3300 -1075) $PN 1
J 0
(-3295 -1113);
DISPLAY 0.787234 (-3295 -1113);
PAINT MONO (-3295 -1113);
FORCEPROP 1 LASTPIN (-3300 -1275) $PN 2
J 0
(-3295 -1265);
DISPLAY 0.787234 (-3295 -1265);
PAINT MONO (-3295 -1265);
FORCEPROP 1 LAST PACK_TYPE 0402LF
J 0
(-3260 -1350);
DISPLAY 0.787234 (-3260 -1350);
FORCEPROP 1 LAST WATTAGE 1/16W
J 0
(-3260 -1200);
DISPLAY 0.787234 (-3260 -1200);
FORCEPROP 1 LAST VALUE 86.6K
J 0
(-3255 -1100);
DISPLAY 0.787234 (-3255 -1100);
FORCEPROP 1 LAST TOLERANCE 1%
J 0
(-3255 -1150);
DISPLAY 0.787234 (-3255 -1150);
FORCEPROP 1 LAST MATERIAL EMPTY
J 0
(-3260 -1250);
DISPLAY 0.787234 (-3260 -1250);
PAINT RED (-3260 -1250);
FORCEPROP 2 LAST CDS_LIB pure_quanta
J 0
(-3300 -1175);
DISPLAY INVISIBLE (-3300 -1175);
FORCEPROP 1 LAST PATH I2
J 0
(-3250 -1000);
DISPLAY 0.978723 (-3250 -1000);
PAINT WHITE (-3250 -1000);
DISPLAY INVISIBLE (-3250 -1000);
FORCEPROP 1 LAST PART_NUMBER CS38662FB05
J 0
(-3260 -1300);
DISPLAY 0.787234 (-3260 -1300);
DISPLAY INVISIBLE (-3260 -1300);
FORCEADD Q_RES..1
(-1800 -150);
FORCEPROP 1 LAST LOCATION PR8389
J 0
(-1850 -100);
DISPLAY 0.617021 (-1850 -100);
PAINT AQUA (-1850 -100);
FORCEPROP 0 LAST $SEC 1
J 0
(-1850 -50);
DISPLAY 0.680851 (-1850 -50);
PAINT MONO (-1850 -50);
DISPLAY INVISIBLE (-1850 -50);
FORCEPROP 0 LAST CDS_SEC 1
J 0
(-1850 -50);
DISPLAY 1.021277 (-1850 -50);
DISPLAY INVISIBLE (-1850 -50);
FORCEPROP 1 LASTPIN (-1900 -150) $PN 1
J 0
(-1888 -138);
DISPLAY 0.617021 (-1888 -138);
PAINT MONO (-1888 -138);
FORCEPROP 1 LASTPIN (-1700 -150) $PN 2
J 0
(-1738 -138);
DISPLAY 0.617021 (-1738 -138);
PAINT MONO (-1738 -138);
FORCEPROP 1 LAST WATTAGE 1/16W
J 2
(-1450 -100);
DISPLAY 0.617021 (-1450 -100);
PAINT SKYBLUE (-1450 -100);
FORCEPROP 1 LAST TOLERANCE 1%
J 0
(-1675 -100);
DISPLAY 0.617021 (-1675 -100);
PAINT SKYBLUE (-1675 -100);
FORCEPROP 1 LAST PACK_TYPE 0402LF
J 0
(-1425 -150);
DISPLAY 0.617021 (-1425 -150);
PAINT SKYBLUE (-1425 -150);
FORCEPROP 1 LAST MATERIAL CHIP
J 0
(-1575 -150);
DISPLAY 0.617021 (-1575 -150);
PAINT SKYBLUE (-1575 -150);
FORCEPROP 1 LAST VALUE 1
J 2
(-1650 -150);
DISPLAY 0.617021 (-1650 -150);
PAINT SKYBLUE (-1650 -150);
FORCEPROP 2 LAST CDS_LIB pure_quanta
J 0
(-1800 -150);
DISPLAY INVISIBLE (-1800 -150);
FORCEPROP 1 LAST PATH I20
J 0
(-1850 0);
DISPLAY 0.978723 (-1850 0);
PAINT WHITE (-1850 0);
DISPLAY INVISIBLE (-1850 0);
FORCEPROP 1 LAST PART_NUMBER CS-1002FB04
J 0
(-1850 -50);
DISPLAY 0.617021 (-1850 -50);
PAINT BLUE (-1850 -50);
DISPLAY INVISIBLE (-1850 -50);
FORCEADD NCP3284AMNTXG..1
(-100 -500);
FORCEPROP 1 LAST LOCATION PU9
J 0
(-400 375);
DISPLAY 0.723404 (-400 375);
PAINT GREEN (-400 375);
FORCEPROP 0 LAST $SEC 1
J 0
(-400 525);
DISPLAY 0.680851 (-400 525);
PAINT MONO (-400 525);
DISPLAY INVISIBLE (-400 525);
FORCEPROP 0 LAST CDS_SEC 1
J 0
(-400 525);
DISPLAY 1.021277 (-400 525);
DISPLAY INVISIBLE (-400 525);
FORCEPROP 0 LASTPIN (300 -1100) $PN 32
J 0
(310 -1090);
DISPLAY 0.680851 (310 -1090);
PAINT MONO (310 -1090);
FORCEPROP 0 LASTPIN (300 -100) $PN 26
J 0
(310 -90);
DISPLAY 0.680851 (310 -90);
PAINT MONO (310 -90);
FORCEPROP 0 LASTPIN (-550 -300) $PN 27
J 2
(-560 -290);
DISPLAY 0.680851 (-560 -290);
PAINT MONO (-560 -290);
FORCEPROP 0 LASTPIN (300 -700) $PN 30
J 0
(310 -690);
DISPLAY 0.680851 (310 -690);
PAINT MONO (310 -690);
FORCEPROP 0 LASTPIN (-550 -450) $PN 6
J 2
(-560 -440);
DISPLAY 0.680851 (-560 -440);
PAINT MONO (-560 -440);
FORCEPROP 0 LASTPIN (-550 -500) $PN 37
J 2
(-560 -490);
DISPLAY 0.680851 (-560 -490);
PAINT MONO (-560 -490);
FORCEPROP 0 LASTPIN (-550 -650) $PN 35
J 2
(-560 -640);
DISPLAY 0.680851 (-560 -640);
PAINT MONO (-560 -640);
FORCEPROP 0 LASTPIN (-550 -950) $PN 1
J 2
(-560 -940);
DISPLAY 0.680851 (-560 -940);
PAINT MONO (-560 -940);
FORCEPROP 0 LASTPIN (-550 -750) $PN 36
J 2
(-560 -740);
DISPLAY 0.680851 (-560 -740);
PAINT MONO (-560 -740);
FORCEPROP 0 LASTPIN (-550 -1100) $PN 33
J 2
(-560 -1090);
DISPLAY 0.680851 (-560 -1090);
PAINT MONO (-560 -1090);
FORCEPROP 0 LASTPIN (-550 -1150) $PN 34
J 2
(-560 -1140);
DISPLAY 0.680851 (-560 -1140);
PAINT MONO (-560 -1140);
FORCEPROP 0 LASTPIN (300 -1150) $PN 7_10-19
J 0
(310 -1140);
DISPLAY 0.680851 (310 -1140);
PAINT MONO (310 -1140);
FORCEPROP 0 LASTPIN (300 150) $PN 2
J 0
(310 160);
DISPLAY 0.680851 (310 160);
PAINT MONO (310 160);
FORCEPROP 0 LASTPIN (300 -300) $PN 25
J 0
(310 -290);
DISPLAY 0.680851 (310 -290);
PAINT MONO (310 -290);
FORCEPROP 0 LASTPIN (-550 100) $PN 20_24
J 2
(-560 110);
DISPLAY 0.680851 (-560 110);
PAINT MONO (-560 110);
FORCEPROP 0 LASTPIN (-550 -850) $PN 29
J 2
(-560 -840);
DISPLAY 0.680851 (-560 -840);
PAINT MONO (-560 -840);
FORCEPROP 0 LASTPIN (300 -500) $PN 11_18
J 0
(310 -490);
DISPLAY 0.680851 (310 -490);
PAINT MONO (310 -490);
FORCEPROP 0 LASTPIN (-550 -100) $PN 4
J 2
(-560 -90);
DISPLAY 0.680851 (-560 -90);
PAINT MONO (-560 -90);
FORCEPROP 0 LASTPIN (-550 -50) $PN 5
J 2
(-560 -40);
DISPLAY 0.680851 (-560 -40);
PAINT MONO (-560 -40);
FORCEPROP 0 LASTPIN (-550 150) $PN 3
J 2
(-560 160);
DISPLAY 0.680851 (-560 160);
PAINT MONO (-560 160);
FORCEPROP 0 LASTPIN (300 -1000) $PN 28
J 0
(310 -990);
DISPLAY 0.680851 (310 -990);
PAINT MONO (310 -990);
FORCEPROP 0 LASTPIN (300 -950) $PN 31
J 0
(310 -940);
DISPLAY 0.680851 (310 -940);
PAINT MONO (310 -940);
FORCEPROP 2 LAST VALUE NCP3284AMNTXG
J 0
(-400 425);
DISPLAY 0.617021 (-400 425);
PAINT SKYBLUE (-400 425);
FORCEPROP 1 LAST MATERIAL IC
J 0
(-400 225);
DISPLAY 0.723404 (-400 225);
PAINT GREEN (-400 225);
FORCEPROP 2 LAST PART_TYPE SMLF
J 0
(-400 475);
DISPLAY 1.021277 (-400 475);
FORCEPROP 2 LAST CDS_LIB pure_quanta
J 0
(-100 -500);
DISPLAY INVISIBLE (-100 -500);
FORCEPROP 1 LAST NEEDS_NO_SIZE TRUE
J 0
(-100 -500);
DISPLAY 0.723404 (-100 -500);
PAINT GREEN (-100 -500);
DISPLAY INVISIBLE (-100 -500);
FORCEPROP 1 LAST CDS_LMAN_SYM_OUTLINE -300,700,250,-700
J 0
(-100 -500);
DISPLAY 0.468085 (-100 -500);
PAINT GREEN (-100 -500);
DISPLAY INVISIBLE (-100 -500);
FORCEPROP 1 LAST PATH I21
J 0
(-100 -500);
DISPLAY 0.723404 (-100 -500);
PAINT GREEN (-100 -500);
DISPLAY INVISIBLE (-100 -500);
FORCEPROP 1 LAST PART_NUMBER AL003284002
J 0
(-400 300);
DISPLAY 0.723404 (-400 300);
PAINT GREEN (-400 300);
DISPLAY INVISIBLE (-400 300);
FORCEADD GND..1
(-4525 850);
FORCEPROP 3 LASTPIN (-4525 900) SIG_NAME GND\g
J 0
(-4515 910);
DISPLAY 0.659574 (-4515 910);
PAINT MONO (-4515 910);
DISPLAY INVISIBLE (-4515 910);
FORCEPROP 2 LAST CDS_LIB pure_quanta_power
J 0
(-4525 850);
DISPLAY INVISIBLE (-4525 850);
FORCEPROP 1 LAST SIZE 1B
J 0
(-4450 800);
DISPLAY 0.872340 (-4450 800);
PAINT AQUA (-4450 800);
DISPLAY INVISIBLE (-4450 800);
FORCEPROP 1 LAST HDL_POWER GND
J 0
(-4525 1000);
DISPLAY 0.872340 (-4525 1000);
PAINT GREEN (-4525 1000);
DISPLAY INVISIBLE (-4525 1000);
FORCEPROP 1 LAST PATH I22
J 0
(-4450 850);
DISPLAY 0.872340 (-4450 850);
PAINT AQUA (-4450 850);
DISPLAY INVISIBLE (-4450 850);
FORCEADD Q_CAP..1
(-4525 1100);
FORCEPROP 1 LAST LOCATION PC1649
J 0
(-4475 1200);
DISPLAY 0.787234 (-4475 1200);
FORCEPROP 0 LAST $SEC 1
J 0
(-4475 1250);
DISPLAY 0.680851 (-4475 1250);
PAINT MONO (-4475 1250);
DISPLAY INVISIBLE (-4475 1250);
FORCEPROP 0 LAST CDS_SEC 1
J 0
(-4475 1250);
DISPLAY 1.021277 (-4475 1250);
DISPLAY INVISIBLE (-4475 1250);
FORCEPROP 1 LASTPIN (-4525 1200) $PN 1
J 0
(-4515 1180);
DISPLAY 0.787234 (-4515 1180);
PAINT MONO (-4515 1180);
FORCEPROP 1 LASTPIN (-4525 1000) $PN 2
J 0
(-4515 980);
DISPLAY 0.787234 (-4515 980);
PAINT MONO (-4515 980);
FORCEPROP 1 LAST TOLERANCE 10%
J 0
(-4475 1050);
DISPLAY 0.787234 (-4475 1050);
FORCEPROP 1 LAST VALUE 0.1UF
J 0
(-4475 1150);
DISPLAY 0.787234 (-4475 1150);
FORCEPROP 1 LAST MATERIAL X6S
J 0
(-4475 1000);
DISPLAY 0.787234 (-4475 1000);
FORCEPROP 1 LAST VOLTAGE 25V
J 0
(-4475 1100);
DISPLAY 0.787234 (-4475 1100);
FORCEPROP 1 LAST PACK_TYPE C0402
J 0
(-4475 900);
DISPLAY 0.787234 (-4475 900);
FORCEPROP 2 LAST CDS_LIB pure_quanta
J 0
(-4525 1100);
DISPLAY INVISIBLE (-4525 1100);
FORCEPROP 1 LAST PATH I23
J 0
(-4475 1250);
DISPLAY 0.978723 (-4475 1250);
PAINT WHITE (-4475 1250);
DISPLAY INVISIBLE (-4475 1250);
FORCEPROP 1 LAST PART_NUMBER CH4104KEB00
J 0
(-4475 950);
DISPLAY 0.787234 (-4475 950);
DISPLAY INVISIBLE (-4475 950);
FORCEADD Q_INDUCTOR..1
(-4300 1325);
FORCEPROP 1 LAST LOCATION PL8045
J 0
(-4425 1485);
DISPLAY 0.617021 (-4425 1485);
PAINT AQUA (-4425 1485);
FORCEPROP 0 LAST $SEC 1
J 0
(-4425 1625);
DISPLAY 0.680851 (-4425 1625);
PAINT MONO (-4425 1625);
DISPLAY INVISIBLE (-4425 1625);
FORCEPROP 0 LAST CDS_SEC 1
J 0
(-4425 1625);
DISPLAY 1.021277 (-4425 1625);
DISPLAY INVISIBLE (-4425 1625);
FORCEPROP 0 LASTPIN (-4400 1300) $PN 1
J 2
(-4410 1310);
DISPLAY 0.617021 (-4410 1310);
PAINT MONO (-4410 1310);
FORCEPROP 0 LASTPIN (-4200 1300) $PN 2
J 0
(-4190 1310);
DISPLAY 0.617021 (-4190 1310);
PAINT MONO (-4190 1310);
FORCEPROP 2 LAST PACK_TYPE SMLF
J 0
(-4425 1525);
DISPLAY 0.617021 (-4425 1525);
PAINT SKYBLUE (-4425 1525);
FORCEPROP 1 LAST MATERIAL IND
J 0
(-4425 1380);
DISPLAY 0.617021 (-4425 1380);
PAINT SKYBLUE (-4425 1380);
FORCEPROP 2 LAST VALUE 100NH/16A
J 0
(-4425 1575);
DISPLAY 0.617021 (-4425 1575);
PAINT SKYBLUE (-4425 1575);
FORCEPROP 2 LAST CDS_LIB pure_quanta
J 0
(-4300 1325);
DISPLAY INVISIBLE (-4300 1325);
FORCEPROP 1 LAST NEEDS_NO_SIZE TRUE
J 0
(-4300 1325);
DISPLAY 0.468085 (-4300 1325);
PAINT GREEN (-4300 1325);
DISPLAY INVISIBLE (-4300 1325);
FORCEPROP 1 LAST PATH I24
J 0
(-4225 1380);
DISPLAY 0.723404 (-4225 1380);
PAINT GREEN (-4225 1380);
DISPLAY INVISIBLE (-4225 1380);
FORCEPROP 1 LAST PART_NUMBER CV+10G0MZ04
J 0
(-4425 1435);
DISPLAY 0.617021 (-4425 1435);
PAINT SKYBLUE (-4425 1435);
DISPLAY INVISIBLE (-4425 1435);
FORCEADD UNIVERSAL_POWER..1
(-4525 1725);
FORCEPROP 3 LASTPIN (-4525 1675) SIG_NAME P12V_AUX\g
J 0
(-4515 1685);
DISPLAY 0.659574 (-4515 1685);
PAINT MONO (-4515 1685);
DISPLAY INVISIBLE (-4515 1685);
FORCEPROP 1 LAST HDL_POWER P12V_AUX
J 1
(-4525 1775);
DISPLAY 0.617021 (-4525 1775);
PAINT GREEN (-4525 1775);
FORCEPROP 2 LAST CDS_LIB pure_quanta_power
J 0
(-4525 1725);
PAINT MONO (-4525 1725);
DISPLAY INVISIBLE (-4525 1725);
FORCEPROP 1 LAST PATH I25
J 0
(-4475 1750);
DISPLAY 0.872340 (-4475 1750);
PAINT AQUA (-4475 1750);
DISPLAY INVISIBLE (-4475 1750);
FORCEADD Q_CAP..1
(-4050 450);
FORCEPROP 1 LAST LOCATION PC2260
J 0
(-4000 550);
DISPLAY 0.617021 (-4000 550);
PAINT AQUA (-4000 550);
FORCEPROP 0 LAST $SEC 1
J 0
(-4000 600);
DISPLAY 0.680851 (-4000 600);
PAINT MONO (-4000 600);
DISPLAY INVISIBLE (-4000 600);
FORCEPROP 0 LAST CDS_SEC 1
J 0
(-4000 600);
DISPLAY 1.021277 (-4000 600);
DISPLAY INVISIBLE (-4000 600);
FORCEPROP 1 LASTPIN (-4050 550) $PN 1
J 0
(-4040 530);
DISPLAY 0.787234 (-4040 530);
PAINT MONO (-4040 530);
FORCEPROP 1 LASTPIN (-4050 350) $PN 2
J 0
(-4040 330);
DISPLAY 0.787234 (-4040 330);
PAINT MONO (-4040 330);
FORCEPROP 1 LAST PACK_TYPE C0805
J 0
(-4000 250);
DISPLAY 0.617021 (-4000 250);
PAINT SKYBLUE (-4000 250);
FORCEPROP 1 LAST TOLERANCE 20%
J 0
(-4000 400);
DISPLAY 0.617021 (-4000 400);
PAINT SKYBLUE (-4000 400);
FORCEPROP 1 LAST MATERIAL X6S
J 0
(-4000 350);
DISPLAY 0.617021 (-4000 350);
PAINT SKYBLUE (-4000 350);
FORCEPROP 1 LAST VALUE 22UF
J 0
(-4000 500);
DISPLAY 0.617021 (-4000 500);
PAINT SKYBLUE (-4000 500);
FORCEPROP 1 LAST VOLTAGE 16V
J 0
(-4000 450);
DISPLAY 0.617021 (-4000 450);
PAINT SKYBLUE (-4000 450);
FORCEPROP 2 LAST CDS_LIB pure_quanta
J 0
(-4050 450);
DISPLAY INVISIBLE (-4050 450);
FORCEPROP 1 LAST PATH I26
J 0
(-4000 600);
DISPLAY 0.978723 (-4000 600);
PAINT WHITE (-4000 600);
DISPLAY INVISIBLE (-4000 600);
FORCEPROP 1 LAST PART_NUMBER CH6223MEA01
J 0
(-4000 300);
DISPLAY 0.489362 (-4000 300);
PAINT BLUE (-4000 300);
DISPLAY INVISIBLE (-4000 300);
FORCEADD Q_CAP..1
(-3725 450);
FORCEPROP 1 LAST LOCATION PC2261
J 0
(-3675 550);
DISPLAY 0.617021 (-3675 550);
PAINT AQUA (-3675 550);
FORCEPROP 0 LAST $SEC 1
J 0
(-3675 600);
DISPLAY 0.680851 (-3675 600);
PAINT MONO (-3675 600);
DISPLAY INVISIBLE (-3675 600);
FORCEPROP 0 LAST CDS_SEC 1
J 0
(-3675 600);
DISPLAY 1.021277 (-3675 600);
DISPLAY INVISIBLE (-3675 600);
FORCEPROP 1 LASTPIN (-3725 550) $PN 1
J 0
(-3715 530);
DISPLAY 0.787234 (-3715 530);
PAINT MONO (-3715 530);
FORCEPROP 1 LASTPIN (-3725 350) $PN 2
J 0
(-3715 330);
DISPLAY 0.787234 (-3715 330);
PAINT MONO (-3715 330);
FORCEPROP 1 LAST VALUE 22UF
J 0
(-3675 500);
DISPLAY 0.617021 (-3675 500);
PAINT SKYBLUE (-3675 500);
FORCEPROP 1 LAST TOLERANCE 20%
J 0
(-3675 400);
DISPLAY 0.617021 (-3675 400);
PAINT SKYBLUE (-3675 400);
FORCEPROP 1 LAST VOLTAGE 16V
J 0
(-3675 450);
DISPLAY 0.617021 (-3675 450);
PAINT SKYBLUE (-3675 450);
FORCEPROP 1 LAST MATERIAL X6S
J 0
(-3675 350);
DISPLAY 0.617021 (-3675 350);
PAINT SKYBLUE (-3675 350);
FORCEPROP 1 LAST PACK_TYPE C0805
J 0
(-3675 250);
DISPLAY 0.617021 (-3675 250);
PAINT SKYBLUE (-3675 250);
FORCEPROP 2 LAST CDS_LIB pure_quanta
J 0
(-3725 450);
DISPLAY INVISIBLE (-3725 450);
FORCEPROP 1 LAST PATH I27
J 0
(-3675 600);
DISPLAY 0.978723 (-3675 600);
PAINT WHITE (-3675 600);
DISPLAY INVISIBLE (-3675 600);
FORCEPROP 1 LAST PART_NUMBER CH6223MEA01
J 0
(-3675 300);
DISPLAY 0.489362 (-3675 300);
PAINT BLUE (-3675 300);
DISPLAY INVISIBLE (-3675 300);
FORCEADD GND..1
(-3975 725);
FORCEPROP 3 LASTPIN (-3975 775) SIG_NAME GND\g
J 0
(-3965 785);
DISPLAY 0.659574 (-3965 785);
PAINT MONO (-3965 785);
DISPLAY INVISIBLE (-3965 785);
FORCEPROP 1 LAST SIZE 1B
J 0
(-3900 675);
DISPLAY 0.872340 (-3900 675);
PAINT AQUA (-3900 675);
DISPLAY INVISIBLE (-3900 675);
FORCEPROP 2 LAST CDS_LIB pure_quanta_power
J 0
(-3975 725);
PAINT MONO (-3975 725);
DISPLAY INVISIBLE (-3975 725);
FORCEPROP 1 LAST HDL_POWER GND
J 0
(-3975 875);
DISPLAY 0.872340 (-3975 875);
PAINT GREEN (-3975 875);
DISPLAY INVISIBLE (-3975 875);
FORCEPROP 1 LAST PATH I28
J 0
(-3900 725);
DISPLAY 0.872340 (-3900 725);
PAINT AQUA (-3900 725);
DISPLAY INVISIBLE (-3900 725);
FORCEADD Q_CAPP..1
(-3975 1100);
FORCEPROP 1 LAST LOCATION PC3
J 0
(-3925 1225);
DISPLAY 0.617021 (-3925 1225);
PAINT AQUA (-3925 1225);
FORCEPROP 0 LAST $SEC 1
J 0
(-3925 1275);
DISPLAY 0.680851 (-3925 1275);
PAINT MONO (-3925 1275);
DISPLAY INVISIBLE (-3925 1275);
FORCEPROP 0 LAST CDS_SEC 1
J 0
(-3925 1275);
DISPLAY 1.021277 (-3925 1275);
DISPLAY INVISIBLE (-3925 1275);
FORCEPROP 1 LASTPIN (-3975 1200) $PN 1
J 0
(-3965 1185);
DISPLAY 0.787234 (-3965 1185);
PAINT MONO (-3965 1185);
FORCEPROP 1 LASTPIN (-3975 1000) $PN 2
J 0
(-3965 985);
DISPLAY 0.787234 (-3965 985);
PAINT MONO (-3965 985);
FORCEPROP 1 LAST VOLTAGE 16V
J 0
(-3925 1075);
DISPLAY 0.617021 (-3925 1075);
PAINT SKYBLUE (-3925 1075);
FORCEPROP 1 LAST TOLERANCE 20%
J 0
(-3925 1125);
DISPLAY 0.617021 (-3925 1125);
PAINT SKYBLUE (-3925 1125);
FORCEPROP 1 LAST VALUE 270UF
J 0
(-3925 1175);
DISPLAY 0.617021 (-3925 1175);
PAINT SKYBLUE (-3925 1175);
FORCEPROP 1 LAST PACK_TYPE THLF
J 0
(-3925 975);
DISPLAY 0.617021 (-3925 975);
PAINT SKYBLUE (-3925 975);
FORCEPROP 1 LAST MATERIAL OSCON
J 0
(-3925 1025);
DISPLAY 0.617021 (-3925 1025);
PAINT SKYBLUE (-3925 1025);
FORCEPROP 2 LAST CDS_LIB pure_quanta
J 0
(-3975 1100);
DISPLAY INVISIBLE (-3975 1100);
FORCEPROP 1 LAST PATH I29
J 0
(-3925 1250);
DISPLAY 0.978723 (-3925 1250);
DISPLAY INVISIBLE (-3925 1250);
FORCEPROP 1 LAST PART_NUMBER CC72703MD38
J 0
(-3925 925);
DISPLAY 0.489362 (-3925 925);
PAINT BLUE (-3925 925);
DISPLAY INVISIBLE (-3925 925);
FORCEPROP 1 LAST LOCATION PC3
J 0
(-3925 1275);
DISPLAY 1.021277 (-3925 1275);
PAINT AQUA (-3925 1275);
DISPLAY INVISIBLE (-3925 1275);
FORCEADD GND..1
(-4050 100);
FORCEPROP 3 LASTPIN (-4050 150) SIG_NAME GND\g
J 0
(-4040 160);
DISPLAY 0.659574 (-4040 160);
PAINT MONO (-4040 160);
DISPLAY INVISIBLE (-4040 160);
FORCEPROP 1 LAST SIZE 1B
J 0
(-3975 50);
DISPLAY 0.872340 (-3975 50);
PAINT AQUA (-3975 50);
DISPLAY INVISIBLE (-3975 50);
FORCEPROP 2 LAST CDS_LIB pure_quanta_power
J 0
(-4050 100);
DISPLAY INVISIBLE (-4050 100);
FORCEPROP 1 LAST HDL_POWER GND
J 0
(-4050 250);
DISPLAY 0.872340 (-4050 250);
PAINT GREEN (-4050 250);
DISPLAY INVISIBLE (-4050 250);
FORCEPROP 1 LAST PATH I3
J 0
(-3975 100);
DISPLAY 0.872340 (-3975 100);
PAINT AQUA (-3975 100);
DISPLAY INVISIBLE (-3975 100);
FORCEADD Q_CAPP..1
(-3675 1100);
FORCEPROP 1 LAST LOCATION PC566
J 0
(-3625 1225);
DISPLAY 0.617021 (-3625 1225);
PAINT AQUA (-3625 1225);
FORCEPROP 0 LAST $SEC 1
J 0
(-3625 1275);
DISPLAY 0.680851 (-3625 1275);
PAINT MONO (-3625 1275);
DISPLAY INVISIBLE (-3625 1275);
FORCEPROP 0 LAST CDS_SEC 1
J 0
(-3625 1275);
DISPLAY 1.021277 (-3625 1275);
DISPLAY INVISIBLE (-3625 1275);
FORCEPROP 1 LASTPIN (-3675 1200) $PN 1
J 0
(-3665 1185);
DISPLAY 0.617021 (-3665 1185);
PAINT MONO (-3665 1185);
FORCEPROP 1 LASTPIN (-3675 1000) $PN 2
J 0
(-3665 985);
DISPLAY 0.617021 (-3665 985);
PAINT MONO (-3665 985);
FORCEPROP 1 LAST MATERIAL OSCON
J 0
(-3625 1025);
DISPLAY 0.617021 (-3625 1025);
PAINT SKYBLUE (-3625 1025);
FORCEPROP 1 LAST VOLTAGE 16V
J 0
(-3625 1075);
DISPLAY 0.617021 (-3625 1075);
PAINT SKYBLUE (-3625 1075);
FORCEPROP 1 LAST VALUE 270UF
J 0
(-3625 1175);
DISPLAY 0.617021 (-3625 1175);
PAINT SKYBLUE (-3625 1175);
FORCEPROP 1 LAST TOLERANCE 20%
J 0
(-3625 1125);
DISPLAY 0.617021 (-3625 1125);
PAINT SKYBLUE (-3625 1125);
FORCEPROP 1 LAST PACK_TYPE THLF
J 0
(-3625 975);
DISPLAY 0.617021 (-3625 975);
PAINT SKYBLUE (-3625 975);
FORCEPROP 2 LAST CDS_LIB pure_quanta
J 0
(-3675 1100);
DISPLAY INVISIBLE (-3675 1100);
FORCEPROP 1 LAST PATH I30
J 0
(-3625 1250);
DISPLAY 0.978723 (-3625 1250);
DISPLAY INVISIBLE (-3625 1250);
FORCEPROP 1 LAST PART_NUMBER CC72703MD38
J 0
(-3625 925);
DISPLAY 0.489362 (-3625 925);
PAINT BLUE (-3625 925);
DISPLAY INVISIBLE (-3625 925);
FORCEPROP 1 LAST LOCATION PC566
J 0
(-3625 1275);
DISPLAY 1.021277 (-3625 1275);
PAINT AQUA (-3625 1275);
DISPLAY INVISIBLE (-3625 1275);
FORCEADD Q_CAP..1
(-3400 450);
FORCEPROP 1 LAST LOCATION PC2262
J 0
(-3350 550);
DISPLAY 0.617021 (-3350 550);
PAINT AQUA (-3350 550);
FORCEPROP 0 LAST $SEC 1
J 0
(-3350 600);
DISPLAY 0.680851 (-3350 600);
PAINT MONO (-3350 600);
DISPLAY INVISIBLE (-3350 600);
FORCEPROP 0 LAST CDS_SEC 1
J 0
(-3350 600);
DISPLAY 1.021277 (-3350 600);
DISPLAY INVISIBLE (-3350 600);
FORCEPROP 1 LASTPIN (-3400 550) $PN 1
J 0
(-3390 530);
DISPLAY 0.787234 (-3390 530);
PAINT MONO (-3390 530);
FORCEPROP 1 LASTPIN (-3400 350) $PN 2
J 0
(-3390 330);
DISPLAY 0.787234 (-3390 330);
PAINT MONO (-3390 330);
FORCEPROP 1 LAST VOLTAGE 16V
J 0
(-3350 450);
DISPLAY 0.617021 (-3350 450);
PAINT SKYBLUE (-3350 450);
FORCEPROP 1 LAST PACK_TYPE C0805
J 0
(-3350 250);
DISPLAY 0.617021 (-3350 250);
PAINT SKYBLUE (-3350 250);
FORCEPROP 1 LAST MATERIAL X6S
J 0
(-3350 350);
DISPLAY 0.617021 (-3350 350);
PAINT SKYBLUE (-3350 350);
FORCEPROP 1 LAST TOLERANCE 20%
J 0
(-3350 400);
DISPLAY 0.617021 (-3350 400);
PAINT SKYBLUE (-3350 400);
FORCEPROP 1 LAST VALUE 22UF
J 0
(-3350 500);
DISPLAY 0.617021 (-3350 500);
PAINT SKYBLUE (-3350 500);
FORCEPROP 2 LAST CDS_LIB pure_quanta
J 0
(-3400 450);
DISPLAY INVISIBLE (-3400 450);
FORCEPROP 1 LAST PATH I31
J 0
(-3350 600);
DISPLAY 0.978723 (-3350 600);
PAINT WHITE (-3350 600);
DISPLAY INVISIBLE (-3350 600);
FORCEPROP 1 LAST PART_NUMBER CH6223MEA01
J 0
(-3350 300);
DISPLAY 0.489362 (-3350 300);
PAINT BLUE (-3350 300);
DISPLAY INVISIBLE (-3350 300);
FORCEADD Q_CAP..1
(-3350 1100);
FORCEPROP 1 LAST LOCATION PC8567
J 0
(-3300 1200);
DISPLAY 0.617021 (-3300 1200);
PAINT AQUA (-3300 1200);
FORCEPROP 0 LAST $SEC 1
J 0
(-3300 1250);
DISPLAY 0.680851 (-3300 1250);
PAINT MONO (-3300 1250);
DISPLAY INVISIBLE (-3300 1250);
FORCEPROP 2 LAST CDS_SEC 1
J 0
(-3300 1300);
DISPLAY 1.021277 (-3300 1300);
DISPLAY INVISIBLE (-3300 1300);
FORCEPROP 1 LASTPIN (-3350 1200) $PN 1
J 0
(-3340 1180);
DISPLAY 0.787234 (-3340 1180);
PAINT MONO (-3340 1180);
DISPLAY INVISIBLE (-3340 1180);
FORCEPROP 1 LASTPIN (-3350 1000) $PN 2
J 0
(-3340 980);
DISPLAY 0.787234 (-3340 980);
PAINT MONO (-3340 980);
DISPLAY INVISIBLE (-3340 980);
FORCEPROP 1 LAST MATERIAL X6S
J 0
(-3300 1000);
DISPLAY 0.617021 (-3300 1000);
PAINT SKYBLUE (-3300 1000);
FORCEPROP 1 LAST TOLERANCE 20%
J 0
(-3300 1050);
DISPLAY 0.617021 (-3300 1050);
PAINT SKYBLUE (-3300 1050);
FORCEPROP 1 LAST VOLTAGE 16V
J 0
(-3300 1100);
DISPLAY 0.617021 (-3300 1100);
PAINT SKYBLUE (-3300 1100);
FORCEPROP 1 LAST VALUE 22UF
J 0
(-3300 1150);
DISPLAY 0.617021 (-3300 1150);
PAINT SKYBLUE (-3300 1150);
FORCEPROP 1 LAST PACK_TYPE C0805
J 0
(-3300 900);
DISPLAY 0.617021 (-3300 900);
PAINT SKYBLUE (-3300 900);
FORCEPROP 2 LAST CDS_LIB pure_quanta
J 0
(-3350 1100);
DISPLAY INVISIBLE (-3350 1100);
FORCEPROP 1 LAST PATH I32
J 0
(-3300 1250);
DISPLAY 0.978723 (-3300 1250);
PAINT WHITE (-3300 1250);
DISPLAY INVISIBLE (-3300 1250);
FORCEPROP 1 LAST PART_NUMBER CH6223MEA01
J 0
(-3300 950);
DISPLAY 0.489362 (-3300 950);
PAINT BLUE (-3300 950);
DISPLAY INVISIBLE (-3300 950);
FORCEADD Q_CAP..1
(-3075 450);
FORCEPROP 1 LAST LOCATION PC2263
J 0
(-3025 550);
DISPLAY 0.617021 (-3025 550);
PAINT AQUA (-3025 550);
FORCEPROP 0 LAST $SEC 1
J 0
(-3025 600);
DISPLAY 0.680851 (-3025 600);
PAINT MONO (-3025 600);
DISPLAY INVISIBLE (-3025 600);
FORCEPROP 0 LAST CDS_SEC 1
J 0
(-3025 600);
DISPLAY 1.021277 (-3025 600);
DISPLAY INVISIBLE (-3025 600);
FORCEPROP 1 LASTPIN (-3075 550) $PN 1
J 0
(-3065 530);
DISPLAY 0.787234 (-3065 530);
PAINT MONO (-3065 530);
FORCEPROP 1 LASTPIN (-3075 350) $PN 2
J 0
(-3065 330);
DISPLAY 0.787234 (-3065 330);
PAINT MONO (-3065 330);
FORCEPROP 1 LAST PACK_TYPE C0805
J 0
(-3025 250);
DISPLAY 0.617021 (-3025 250);
PAINT SKYBLUE (-3025 250);
FORCEPROP 1 LAST MATERIAL X6S
J 0
(-3025 350);
DISPLAY 0.617021 (-3025 350);
PAINT SKYBLUE (-3025 350);
FORCEPROP 1 LAST TOLERANCE 20%
J 0
(-3025 400);
DISPLAY 0.617021 (-3025 400);
PAINT SKYBLUE (-3025 400);
FORCEPROP 1 LAST VOLTAGE 16V
J 0
(-3025 450);
DISPLAY 0.617021 (-3025 450);
PAINT SKYBLUE (-3025 450);
FORCEPROP 1 LAST VALUE 22UF
J 0
(-3025 500);
DISPLAY 0.617021 (-3025 500);
PAINT SKYBLUE (-3025 500);
FORCEPROP 2 LAST CDS_LIB pure_quanta
J 0
(-3075 450);
DISPLAY INVISIBLE (-3075 450);
FORCEPROP 1 LAST PATH I33
J 0
(-3025 600);
DISPLAY 0.978723 (-3025 600);
PAINT WHITE (-3025 600);
DISPLAY INVISIBLE (-3025 600);
FORCEPROP 1 LAST PART_NUMBER CH6223MEA01
J 0
(-3025 300);
DISPLAY 0.489362 (-3025 300);
PAINT BLUE (-3025 300);
DISPLAY INVISIBLE (-3025 300);
FORCEADD Q_CAP..1
(-2750 450);
FORCEPROP 1 LAST LOCATION PC2342
J 0
(-2700 550);
DISPLAY 0.617021 (-2700 550);
PAINT AQUA (-2700 550);
FORCEPROP 0 LAST $SEC 1
J 0
(-2700 600);
DISPLAY 0.680851 (-2700 600);
PAINT MONO (-2700 600);
DISPLAY INVISIBLE (-2700 600);
FORCEPROP 0 LAST CDS_SEC 1
J 0
(-2700 600);
DISPLAY 1.021277 (-2700 600);
DISPLAY INVISIBLE (-2700 600);
FORCEPROP 1 LASTPIN (-2750 550) $PN 1
J 0
(-2740 530);
DISPLAY 0.787234 (-2740 530);
PAINT MONO (-2740 530);
FORCEPROP 1 LASTPIN (-2750 350) $PN 2
J 0
(-2740 330);
DISPLAY 0.787234 (-2740 330);
PAINT MONO (-2740 330);
FORCEPROP 1 LAST PACK_TYPE C0805
J 0
(-2700 250);
DISPLAY 0.617021 (-2700 250);
PAINT SKYBLUE (-2700 250);
FORCEPROP 1 LAST TOLERANCE 20%
J 0
(-2700 400);
DISPLAY 0.617021 (-2700 400);
PAINT SKYBLUE (-2700 400);
FORCEPROP 1 LAST MATERIAL X6S
J 0
(-2700 350);
DISPLAY 0.617021 (-2700 350);
PAINT SKYBLUE (-2700 350);
FORCEPROP 1 LAST VOLTAGE 16V
J 0
(-2700 450);
DISPLAY 0.617021 (-2700 450);
PAINT SKYBLUE (-2700 450);
FORCEPROP 1 LAST VALUE 22UF
J 0
(-2700 500);
DISPLAY 0.617021 (-2700 500);
PAINT SKYBLUE (-2700 500);
FORCEPROP 2 LAST CDS_LIB pure_quanta
J 0
(-2750 450);
DISPLAY INVISIBLE (-2750 450);
FORCEPROP 1 LAST PATH I34
J 0
(-2700 600);
DISPLAY 0.978723 (-2700 600);
PAINT WHITE (-2700 600);
DISPLAY INVISIBLE (-2700 600);
FORCEPROP 1 LAST PART_NUMBER CH6223MEA01
J 0
(-2700 300);
DISPLAY 0.489362 (-2700 300);
PAINT BLUE (-2700 300);
DISPLAY INVISIBLE (-2700 300);
FORCEADD Q_CAP..1
(-3025 1100);
FORCEPROP 1 LAST LOCATION PC570
J 0
(-2975 1200);
DISPLAY 0.617021 (-2975 1200);
PAINT AQUA (-2975 1200);
FORCEPROP 0 LAST $SEC 1
J 0
(-2975 1250);
DISPLAY 0.680851 (-2975 1250);
PAINT MONO (-2975 1250);
DISPLAY INVISIBLE (-2975 1250);
FORCEPROP 0 LAST CDS_SEC 1
J 0
(-2975 1250);
DISPLAY 1.021277 (-2975 1250);
DISPLAY INVISIBLE (-2975 1250);
FORCEPROP 1 LASTPIN (-3025 1200) $PN 1
J 0
(-3015 1180);
DISPLAY 0.617021 (-3015 1180);
PAINT MONO (-3015 1180);
FORCEPROP 1 LASTPIN (-3025 1000) $PN 2
J 0
(-3015 980);
DISPLAY 0.617021 (-3015 980);
PAINT MONO (-3015 980);
FORCEPROP 1 LAST VOLTAGE 16V
J 0
(-2975 1100);
DISPLAY 0.617021 (-2975 1100);
PAINT SKYBLUE (-2975 1100);
FORCEPROP 1 LAST VALUE 22UF
J 0
(-2975 1150);
DISPLAY 0.617021 (-2975 1150);
PAINT SKYBLUE (-2975 1150);
FORCEPROP 1 LAST PACK_TYPE C0805
J 0
(-2975 900);
DISPLAY 0.617021 (-2975 900);
PAINT SKYBLUE (-2975 900);
FORCEPROP 1 LAST TOLERANCE 20%
J 0
(-2975 1050);
DISPLAY 0.617021 (-2975 1050);
PAINT SKYBLUE (-2975 1050);
FORCEPROP 1 LAST MATERIAL X6S
J 0
(-2975 1000);
DISPLAY 0.617021 (-2975 1000);
PAINT SKYBLUE (-2975 1000);
FORCEPROP 2 LAST CDS_LIB pure_quanta
J 0
(-3025 1100);
DISPLAY INVISIBLE (-3025 1100);
FORCEPROP 1 LAST PATH I35
J 0
(-2975 1250);
DISPLAY 0.978723 (-2975 1250);
PAINT WHITE (-2975 1250);
DISPLAY INVISIBLE (-2975 1250);
FORCEPROP 1 LAST PART_NUMBER CH6223MEA01
J 0
(-2975 950);
DISPLAY 0.489362 (-2975 950);
PAINT BLUE (-2975 950);
DISPLAY INVISIBLE (-2975 950);
FORCEADD Q_CAP..1
(-2700 1100);
FORCEPROP 1 LAST LOCATION PC571
J 0
(-2650 1200);
DISPLAY 0.617021 (-2650 1200);
PAINT AQUA (-2650 1200);
FORCEPROP 0 LAST $SEC 1
J 0
(-2650 1250);
DISPLAY 0.680851 (-2650 1250);
PAINT MONO (-2650 1250);
DISPLAY INVISIBLE (-2650 1250);
FORCEPROP 0 LAST CDS_SEC 1
J 0
(-2650 1250);
DISPLAY 1.021277 (-2650 1250);
DISPLAY INVISIBLE (-2650 1250);
FORCEPROP 1 LASTPIN (-2700 1200) $PN 1
J 0
(-2690 1180);
DISPLAY 0.617021 (-2690 1180);
PAINT MONO (-2690 1180);
FORCEPROP 1 LASTPIN (-2700 1000) $PN 2
J 0
(-2690 980);
DISPLAY 0.617021 (-2690 980);
PAINT MONO (-2690 980);
FORCEPROP 1 LAST MATERIAL X6S
J 0
(-2650 1000);
DISPLAY 0.617021 (-2650 1000);
PAINT SKYBLUE (-2650 1000);
FORCEPROP 1 LAST VOLTAGE 16V
J 0
(-2650 1100);
DISPLAY 0.617021 (-2650 1100);
PAINT SKYBLUE (-2650 1100);
FORCEPROP 1 LAST VALUE 22UF
J 0
(-2650 1150);
DISPLAY 0.617021 (-2650 1150);
PAINT SKYBLUE (-2650 1150);
FORCEPROP 1 LAST PACK_TYPE C0805
J 0
(-2650 900);
DISPLAY 0.617021 (-2650 900);
PAINT SKYBLUE (-2650 900);
FORCEPROP 1 LAST TOLERANCE 20%
J 0
(-2650 1050);
DISPLAY 0.617021 (-2650 1050);
PAINT SKYBLUE (-2650 1050);
FORCEPROP 2 LAST CDS_LIB pure_quanta
J 0
(-2700 1100);
DISPLAY INVISIBLE (-2700 1100);
FORCEPROP 1 LAST PATH I36
J 0
(-2650 1250);
DISPLAY 0.978723 (-2650 1250);
PAINT WHITE (-2650 1250);
DISPLAY INVISIBLE (-2650 1250);
FORCEPROP 1 LAST PART_NUMBER CH6223MEA01
J 0
(-2650 950);
DISPLAY 0.489362 (-2650 950);
PAINT BLUE (-2650 950);
DISPLAY INVISIBLE (-2650 950);
FORCEADD Q_CAP..1
(-2425 450);
FORCEPROP 1 LAST LOCATION PC2343
J 0
(-2375 550);
DISPLAY 0.617021 (-2375 550);
PAINT AQUA (-2375 550);
FORCEPROP 0 LAST $SEC 1
J 0
(-2375 600);
DISPLAY 0.680851 (-2375 600);
PAINT MONO (-2375 600);
DISPLAY INVISIBLE (-2375 600);
FORCEPROP 0 LAST CDS_SEC 1
J 0
(-2375 600);
DISPLAY 1.021277 (-2375 600);
DISPLAY INVISIBLE (-2375 600);
FORCEPROP 1 LASTPIN (-2425 550) $PN 1
J 0
(-2415 530);
DISPLAY 0.787234 (-2415 530);
PAINT MONO (-2415 530);
FORCEPROP 1 LASTPIN (-2425 350) $PN 2
J 0
(-2415 330);
DISPLAY 0.787234 (-2415 330);
PAINT MONO (-2415 330);
FORCEPROP 1 LAST MATERIAL X6S
J 0
(-2375 350);
DISPLAY 0.617021 (-2375 350);
PAINT SKYBLUE (-2375 350);
FORCEPROP 1 LAST VALUE 22UF
J 0
(-2375 500);
DISPLAY 0.617021 (-2375 500);
PAINT SKYBLUE (-2375 500);
FORCEPROP 1 LAST PACK_TYPE C0805
J 0
(-2375 250);
DISPLAY 0.617021 (-2375 250);
PAINT SKYBLUE (-2375 250);
FORCEPROP 1 LAST VOLTAGE 16V
J 0
(-2375 450);
DISPLAY 0.617021 (-2375 450);
PAINT SKYBLUE (-2375 450);
FORCEPROP 1 LAST TOLERANCE 20%
J 0
(-2375 400);
DISPLAY 0.617021 (-2375 400);
PAINT SKYBLUE (-2375 400);
FORCEPROP 2 LAST CDS_LIB pure_quanta
J 0
(-2425 450);
DISPLAY INVISIBLE (-2425 450);
FORCEPROP 1 LAST PATH I37
J 0
(-2375 600);
DISPLAY 0.978723 (-2375 600);
PAINT WHITE (-2375 600);
DISPLAY INVISIBLE (-2375 600);
FORCEPROP 1 LAST PART_NUMBER CH6223MEA01
J 0
(-2375 300);
DISPLAY 0.489362 (-2375 300);
PAINT BLUE (-2375 300);
DISPLAY INVISIBLE (-2375 300);
FORCEADD Q_CAP..1
(-2100 450);
FORCEPROP 1 LAST LOCATION PC2344
J 0
(-2050 550);
DISPLAY 0.489362 (-2050 550);
PAINT AQUA (-2050 550);
FORCEPROP 0 LAST $SEC 1
J 0
(-2050 600);
DISPLAY 0.680851 (-2050 600);
PAINT MONO (-2050 600);
DISPLAY INVISIBLE (-2050 600);
FORCEPROP 0 LAST CDS_SEC 1
J 0
(-2050 600);
DISPLAY 1.021277 (-2050 600);
DISPLAY INVISIBLE (-2050 600);
FORCEPROP 1 LASTPIN (-2100 550) $PN 1
J 0
(-2090 530);
DISPLAY 0.787234 (-2090 530);
PAINT MONO (-2090 530);
FORCEPROP 1 LASTPIN (-2100 350) $PN 2
J 0
(-2090 330);
DISPLAY 0.787234 (-2090 330);
PAINT MONO (-2090 330);
FORCEPROP 1 LAST VOLTAGE 16V
J 0
(-2050 450);
DISPLAY 0.489362 (-2050 450);
PAINT SKYBLUE (-2050 450);
FORCEPROP 1 LAST PACK_TYPE C0805
J 0
(-2050 250);
DISPLAY 0.489362 (-2050 250);
PAINT SKYBLUE (-2050 250);
FORCEPROP 1 LAST TOLERANCE 20%
J 0
(-2050 400);
DISPLAY 0.489362 (-2050 400);
PAINT SKYBLUE (-2050 400);
FORCEPROP 1 LAST MATERIAL X6S
J 0
(-2050 350);
DISPLAY 0.489362 (-2050 350);
PAINT SKYBLUE (-2050 350);
FORCEPROP 1 LAST VALUE 22UF
J 0
(-2050 500);
DISPLAY 0.489362 (-2050 500);
PAINT SKYBLUE (-2050 500);
FORCEPROP 2 LAST CDS_LIB pure_quanta
J 0
(-2100 450);
DISPLAY INVISIBLE (-2100 450);
FORCEPROP 1 LAST PATH I38
J 0
(-2050 600);
DISPLAY 0.978723 (-2050 600);
PAINT WHITE (-2050 600);
DISPLAY INVISIBLE (-2050 600);
FORCEPROP 1 LAST PART_NUMBER CH6223MEA01
J 0
(-2050 300);
DISPLAY 0.382979 (-2050 300);
PAINT SKYBLUE (-2050 300);
DISPLAY INVISIBLE (-2050 300);
FORCEADD Q_CAP..1
(-2375 1100);
FORCEPROP 1 LAST LOCATION PC576
J 0
(-2325 1200);
DISPLAY 0.617021 (-2325 1200);
PAINT AQUA (-2325 1200);
FORCEPROP 0 LAST $SEC 1
J 0
(-2325 1250);
DISPLAY 0.680851 (-2325 1250);
PAINT MONO (-2325 1250);
DISPLAY INVISIBLE (-2325 1250);
FORCEPROP 0 LAST CDS_SEC 1
J 0
(-2325 1250);
DISPLAY 1.021277 (-2325 1250);
DISPLAY INVISIBLE (-2325 1250);
FORCEPROP 1 LASTPIN (-2375 1200) $PN 1
J 0
(-2365 1180);
DISPLAY 0.617021 (-2365 1180);
PAINT MONO (-2365 1180);
FORCEPROP 1 LASTPIN (-2375 1000) $PN 2
J 0
(-2365 980);
DISPLAY 0.617021 (-2365 980);
PAINT MONO (-2365 980);
FORCEPROP 1 LAST MATERIAL X6S
J 0
(-2325 1000);
DISPLAY 0.617021 (-2325 1000);
PAINT SKYBLUE (-2325 1000);
FORCEPROP 1 LAST PACK_TYPE C0805
J 0
(-2325 900);
DISPLAY 0.617021 (-2325 900);
PAINT SKYBLUE (-2325 900);
FORCEPROP 1 LAST VALUE 22UF
J 0
(-2325 1150);
DISPLAY 0.617021 (-2325 1150);
PAINT SKYBLUE (-2325 1150);
FORCEPROP 1 LAST TOLERANCE 20%
J 0
(-2325 1050);
DISPLAY 0.617021 (-2325 1050);
PAINT SKYBLUE (-2325 1050);
FORCEPROP 1 LAST VOLTAGE 16V
J 0
(-2325 1100);
DISPLAY 0.617021 (-2325 1100);
PAINT SKYBLUE (-2325 1100);
FORCEPROP 2 LAST CDS_LIB pure_quanta
J 0
(-2375 1100);
DISPLAY INVISIBLE (-2375 1100);
FORCEPROP 1 LAST PATH I39
J 0
(-2325 1250);
DISPLAY 0.978723 (-2325 1250);
PAINT WHITE (-2325 1250);
DISPLAY INVISIBLE (-2325 1250);
FORCEPROP 1 LAST PART_NUMBER CH6223MEA01
J 0
(-2325 950);
DISPLAY 0.489362 (-2325 950);
PAINT BLUE (-2325 950);
DISPLAY INVISIBLE (-2325 950);
FORCEADD Q_RES..2
(-3300 -600);
FORCEPROP 1 LAST LOCATION R3117
J 0
(-3255 -475);
DISPLAY 0.787234 (-3255 -475);
FORCEPROP 0 LAST $SEC 1
J 0
(-3250 -425);
DISPLAY 0.680851 (-3250 -425);
PAINT MONO (-3250 -425);
DISPLAY INVISIBLE (-3250 -425);
FORCEPROP 0 LAST CDS_SEC 1
J 0
(-3250 -425);
DISPLAY 1.021277 (-3250 -425);
DISPLAY INVISIBLE (-3250 -425);
FORCEPROP 1 LASTPIN (-3300 -500) $PN 1
J 0
(-3295 -538);
DISPLAY 0.787234 (-3295 -538);
PAINT MONO (-3295 -538);
FORCEPROP 1 LASTPIN (-3300 -700) $PN 2
J 0
(-3295 -690);
DISPLAY 0.787234 (-3295 -690);
PAINT MONO (-3295 -690);
FORCEPROP 1 LAST TOLERANCE 5%
J 0
(-3255 -575);
DISPLAY 0.787234 (-3255 -575);
FORCEPROP 1 LAST VALUE 510K
J 0
(-3255 -525);
DISPLAY 0.787234 (-3255 -525);
FORCEPROP 1 LAST WATTAGE 1/16W
J 0
(-3260 -625);
DISPLAY 0.787234 (-3260 -625);
FORCEPROP 1 LAST MATERIAL EMPTY
J 0
(-3260 -675);
DISPLAY 0.787234 (-3260 -675);
PAINT RED (-3260 -675);
FORCEPROP 1 LAST PACK_TYPE 0402LF
J 0
(-3260 -775);
DISPLAY 0.787234 (-3260 -775);
FORCEPROP 2 LAST CDS_LIB pure_quanta
J 0
(-3300 -600);
DISPLAY INVISIBLE (-3300 -600);
FORCEPROP 1 LAST PATH I4
J 0
(-3250 -425);
DISPLAY 0.978723 (-3250 -425);
PAINT WHITE (-3250 -425);
DISPLAY INVISIBLE (-3250 -425);
FORCEPROP 1 LAST PART_NUMBER CS45102JB03
J 0
(-3260 -725);
DISPLAY 0.787234 (-3260 -725);
DISPLAY INVISIBLE (-3260 -725);
FORCEADD Q_CAP..1
(-2050 1100);
FORCEPROP 1 LAST LOCATION PC8071
J 0
(-2000 1200);
DISPLAY 0.617021 (-2000 1200);
PAINT AQUA (-2000 1200);
FORCEPROP 0 LAST $SEC 1
J 0
(-2000 1250);
DISPLAY 0.680851 (-2000 1250);
PAINT MONO (-2000 1250);
DISPLAY INVISIBLE (-2000 1250);
FORCEPROP 0 LAST CDS_SEC 1
J 0
(-2000 1250);
DISPLAY 1.021277 (-2000 1250);
DISPLAY INVISIBLE (-2000 1250);
FORCEPROP 1 LASTPIN (-2050 1200) $PN 1
J 0
(-2040 1180);
DISPLAY 0.617021 (-2040 1180);
PAINT MONO (-2040 1180);
FORCEPROP 1 LASTPIN (-2050 1000) $PN 2
J 0
(-2040 980);
DISPLAY 0.617021 (-2040 980);
PAINT MONO (-2040 980);
FORCEPROP 1 LAST PACK_TYPE C0805
J 0
(-2000 900);
DISPLAY 0.617021 (-2000 900);
PAINT SKYBLUE (-2000 900);
FORCEPROP 1 LAST TOLERANCE 20%
J 0
(-2000 1050);
DISPLAY 0.617021 (-2000 1050);
PAINT SKYBLUE (-2000 1050);
FORCEPROP 1 LAST MATERIAL X6S
J 0
(-2000 1000);
DISPLAY 0.617021 (-2000 1000);
PAINT SKYBLUE (-2000 1000);
FORCEPROP 1 LAST VOLTAGE 16V
J 0
(-2000 1100);
DISPLAY 0.617021 (-2000 1100);
PAINT SKYBLUE (-2000 1100);
FORCEPROP 1 LAST VALUE 22UF
J 0
(-2000 1150);
DISPLAY 0.617021 (-2000 1150);
PAINT SKYBLUE (-2000 1150);
FORCEPROP 2 LAST CDS_LIB pure_quanta
J 0
(-2050 1100);
DISPLAY INVISIBLE (-2050 1100);
FORCEPROP 1 LAST PATH I40
J 0
(-2000 1250);
DISPLAY 0.978723 (-2000 1250);
PAINT WHITE (-2000 1250);
DISPLAY INVISIBLE (-2000 1250);
FORCEPROP 1 LAST PART_NUMBER CH6223MEA01
J 0
(-2000 950);
DISPLAY 0.489362 (-2000 950);
PAINT BLUE (-2000 950);
DISPLAY INVISIBLE (-2000 950);
FORCEADD Q_CAP..1
(-1725 1100);
FORCEPROP 1 LAST LOCATION PC577
J 0
(-1675 1200);
DISPLAY 0.617021 (-1675 1200);
PAINT AQUA (-1675 1200);
FORCEPROP 0 LAST $SEC 1
J 0
(-1675 1250);
DISPLAY 0.680851 (-1675 1250);
PAINT MONO (-1675 1250);
DISPLAY INVISIBLE (-1675 1250);
FORCEPROP 0 LAST CDS_SEC 1
J 0
(-1675 1250);
DISPLAY 1.021277 (-1675 1250);
DISPLAY INVISIBLE (-1675 1250);
FORCEPROP 1 LASTPIN (-1725 1200) $PN 1
J 0
(-1715 1180);
DISPLAY 0.617021 (-1715 1180);
PAINT MONO (-1715 1180);
FORCEPROP 1 LASTPIN (-1725 1000) $PN 2
J 0
(-1715 980);
DISPLAY 0.617021 (-1715 980);
PAINT MONO (-1715 980);
FORCEPROP 1 LAST PACK_TYPE 0402
J 0
(-1675 900);
DISPLAY 0.617021 (-1675 900);
PAINT SKYBLUE (-1675 900);
FORCEPROP 1 LAST TOLERANCE 10%
J 0
(-1675 1050);
DISPLAY 0.617021 (-1675 1050);
PAINT SKYBLUE (-1675 1050);
FORCEPROP 1 LAST VALUE 0.1UF
J 0
(-1675 1150);
DISPLAY 0.617021 (-1675 1150);
PAINT SKYBLUE (-1675 1150);
FORCEPROP 1 LAST VOLTAGE 25V
J 0
(-1675 1100);
DISPLAY 0.617021 (-1675 1100);
PAINT SKYBLUE (-1675 1100);
FORCEPROP 1 LAST MATERIAL X7R
J 0
(-1675 1000);
DISPLAY 0.617021 (-1675 1000);
PAINT SKYBLUE (-1675 1000);
FORCEPROP 2 LAST CDS_LIB pure_quanta
J 0
(-1725 1100);
DISPLAY INVISIBLE (-1725 1100);
FORCEPROP 1 LAST PATH I41
J 0
(-1675 1250);
DISPLAY 0.978723 (-1675 1250);
PAINT WHITE (-1675 1250);
DISPLAY INVISIBLE (-1675 1250);
FORCEPROP 1 LAST PART_NUMBER CH4104K1B00
J 0
(-1675 950);
DISPLAY 0.489362 (-1675 950);
PAINT BLUE (-1675 950);
DISPLAY INVISIBLE (-1675 950);
FORCEADD UNIVERSAL_POWER..1
(-1150 1050);
FORCEPROP 3 LASTPIN (-1150 1000) SIG_NAME P12V_AUX\g
J 0
(-1140 1010);
DISPLAY 0.659574 (-1140 1010);
PAINT MONO (-1140 1010);
DISPLAY INVISIBLE (-1140 1010);
FORCEPROP 1 LAST HDL_POWER P12V_AUX
J 1
(-1150 1100);
DISPLAY 0.617021 (-1150 1100);
PAINT GREEN (-1150 1100);
FORCEPROP 2 LAST CDS_LIB pure_quanta_power
J 0
(-1150 1050);
DISPLAY INVISIBLE (-1150 1050);
FORCEPROP 1 LAST PATH I42
J 0
(-1100 1075);
DISPLAY 0.872340 (-1100 1075);
PAINT AQUA (-1100 1075);
DISPLAY INVISIBLE (-1100 1075);
FORCEADD GND..1
(-900 450);
FORCEPROP 3 LASTPIN (-900 500) SIG_NAME GND\g
J 0
(-890 510);
DISPLAY 0.659574 (-890 510);
PAINT MONO (-890 510);
DISPLAY INVISIBLE (-890 510);
FORCEPROP 2 LAST CDS_LIB pure_quanta_power
J 0
(-900 450);
DISPLAY INVISIBLE (-900 450);
FORCEPROP 1 LAST SIZE 1B
J 0
(-825 400);
DISPLAY 0.872340 (-825 400);
PAINT AQUA (-825 400);
DISPLAY INVISIBLE (-825 400);
FORCEPROP 1 LAST HDL_POWER GND
J 0
(-900 600);
DISPLAY 0.872340 (-900 600);
PAINT GREEN (-900 600);
DISPLAY INVISIBLE (-900 600);
FORCEPROP 1 LAST PATH I43
J 0
(-825 450);
DISPLAY 0.872340 (-825 450);
PAINT AQUA (-825 450);
DISPLAY INVISIBLE (-825 450);
FORCEADD Q_CAP..1
(-900 725);
FORCEPROP 1 LAST LOCATION PC8008
J 0
(-850 825);
DISPLAY 0.617021 (-850 825);
PAINT AQUA (-850 825);
FORCEPROP 0 LAST $SEC 1
J 0
(-850 875);
DISPLAY 0.680851 (-850 875);
PAINT MONO (-850 875);
DISPLAY INVISIBLE (-850 875);
FORCEPROP 0 LAST CDS_SEC 1
J 0
(-850 875);
DISPLAY 1.021277 (-850 875);
DISPLAY INVISIBLE (-850 875);
FORCEPROP 1 LASTPIN (-900 825) $PN 1
J 0
(-890 805);
DISPLAY 0.787234 (-890 805);
PAINT MONO (-890 805);
FORCEPROP 1 LASTPIN (-900 625) $PN 2
J 0
(-890 605);
DISPLAY 0.787234 (-890 605);
PAINT MONO (-890 605);
FORCEPROP 1 LAST PACK_TYPE 0603
J 0
(-850 525);
DISPLAY 0.617021 (-850 525);
PAINT SKYBLUE (-850 525);
FORCEPROP 1 LAST MATERIAL X7R
J 0
(-850 625);
DISPLAY 0.617021 (-850 625);
PAINT SKYBLUE (-850 625);
FORCEPROP 1 LAST TOLERANCE 10%
J 0
(-850 675);
DISPLAY 0.617021 (-850 675);
PAINT SKYBLUE (-850 675);
FORCEPROP 1 LAST VALUE 1UF
J 0
(-850 775);
DISPLAY 0.617021 (-850 775);
PAINT SKYBLUE (-850 775);
FORCEPROP 1 LAST VOLTAGE 16V
J 0
(-850 725);
DISPLAY 0.617021 (-850 725);
PAINT SKYBLUE (-850 725);
FORCEPROP 2 LAST CDS_LIB pure_quanta
J 0
(-900 725);
DISPLAY INVISIBLE (-900 725);
FORCEPROP 1 LAST PATH I44
J 0
(-850 875);
DISPLAY 0.978723 (-850 875);
PAINT WHITE (-850 875);
DISPLAY INVISIBLE (-850 875);
FORCEPROP 1 LAST PART_NUMBER TMP_QCH5103K1900
J 0
(-850 575);
DISPLAY 0.489362 (-850 575);
PAINT BLUE (-850 575);
DISPLAY INVISIBLE (-850 575);
FORCEADD GND..1
(350 -1250);
FORCEPROP 3 LASTPIN (350 -1200) SIG_NAME GND\g
J 0
(360 -1190);
DISPLAY 0.659574 (360 -1190);
PAINT MONO (360 -1190);
DISPLAY INVISIBLE (360 -1190);
FORCEPROP 1 LAST SIZE 1B
J 0
(425 -1300);
DISPLAY 0.872340 (425 -1300);
PAINT AQUA (425 -1300);
DISPLAY INVISIBLE (425 -1300);
FORCEPROP 2 LAST CDS_LIB pure_quanta_power
J 0
(350 -1250);
DISPLAY INVISIBLE (350 -1250);
FORCEPROP 1 LAST HDL_POWER GND
J 0
(350 -1100);
DISPLAY 0.872340 (350 -1100);
PAINT GREEN (350 -1100);
DISPLAY INVISIBLE (350 -1100);
FORCEPROP 1 LAST PATH I45
J 0
(425 -1250);
DISPLAY 0.872340 (425 -1250);
PAINT AQUA (425 -1250);
DISPLAY INVISIBLE (425 -1250);
FORCEADD Q_RES..1
(825 -1000);
FORCEPROP 1 LAST LOCATION PR836
J 0
(775 -950);
DISPLAY 0.617021 (775 -950);
PAINT AQUA (775 -950);
FORCEPROP 0 LAST $SEC 1
J 0
(775 -900);
DISPLAY 0.680851 (775 -900);
PAINT MONO (775 -900);
DISPLAY INVISIBLE (775 -900);
FORCEPROP 0 LAST CDS_SEC 1
J 0
(775 -900);
DISPLAY 1.021277 (775 -900);
DISPLAY INVISIBLE (775 -900);
FORCEPROP 1 LASTPIN (725 -1000) $PN 1
J 0
(737 -988);
DISPLAY 0.617021 (737 -988);
PAINT MONO (737 -988);
FORCEPROP 1 LASTPIN (925 -1000) $PN 2
J 0
(887 -988);
DISPLAY 0.617021 (887 -988);
PAINT MONO (887 -988);
FORCEPROP 1 LAST WATTAGE 1/16W
J 2
(800 -1150);
DISPLAY 0.617021 (800 -1150);
PAINT SKYBLUE (800 -1150);
FORCEPROP 1 LAST VALUE 1K
J 2
(800 -1100);
DISPLAY 0.617021 (800 -1100);
PAINT SKYBLUE (800 -1100);
FORCEPROP 1 LAST TOLERANCE 1%
J 0
(825 -1100);
DISPLAY 0.617021 (825 -1100);
PAINT SKYBLUE (825 -1100);
FORCEPROP 1 LAST PACK_TYPE 0402LF
J 0
(900 -1100);
DISPLAY 0.617021 (900 -1100);
PAINT SKYBLUE (900 -1100);
FORCEPROP 1 LAST MATERIAL CHIP
J 0
(825 -1150);
DISPLAY 0.617021 (825 -1150);
PAINT SKYBLUE (825 -1150);
FORCEPROP 2 LAST CDS_LIB pure_quanta
J 0
(825 -1000);
DISPLAY INVISIBLE (825 -1000);
FORCEPROP 1 LAST PATH I46
J 0
(775 -850);
DISPLAY 0.978723 (775 -850);
PAINT WHITE (775 -850);
DISPLAY INVISIBLE (775 -850);
FORCEPROP 1 LAST PART_NUMBER CS21002FB06
J 0
(675 -1225);
DISPLAY 0.617021 (675 -1225);
PAINT BLUE (675 -1225);
DISPLAY INVISIBLE (675 -1225);
FORCEADD GND..1
R 1
(550 -950);
FORCEPROP 3 LASTPIN (500 -950) SIG_NAME GND\g
J 0
(510 -940);
DISPLAY 0.659574 (510 -940);
PAINT MONO (510 -940);
DISPLAY INVISIBLE (510 -940);
FORCEPROP 1 LAST SIZE 1B
R 1
J 0
(600 -875);
DISPLAY 0.872340 (600 -875);
PAINT AQUA (600 -875);
DISPLAY INVISIBLE (600 -875);
FORCEPROP 2 LAST CDS_LIB pure_quanta_power
R 1
J 0
(550 -950);
DISPLAY INVISIBLE (550 -950);
FORCEPROP 1 LAST HDL_POWER GND
R 1
J 0
(400 -950);
DISPLAY 0.872340 (400 -950);
PAINT GREEN (400 -950);
DISPLAY INVISIBLE (400 -950);
FORCEPROP 1 LAST PATH I47
R 1
J 0
(550 -875);
DISPLAY 0.872340 (550 -875);
PAINT AQUA (550 -875);
DISPLAY INVISIBLE (550 -875);
FORCEADD Q_CAP..2
(725 -300);
FORCEPROP 1 LAST LOCATION PC568
J 1
(725 -375);
DISPLAY 0.617021 (725 -375);
PAINT AQUA (725 -375);
FORCEPROP 0 LAST $SEC 1
J 0
(975 -300);
DISPLAY 0.680851 (975 -300);
PAINT MONO (975 -300);
DISPLAY INVISIBLE (975 -300);
FORCEPROP 2 LAST CDS_SEC 1
J 0
(725 -50);
DISPLAY 1.021277 (725 -50);
DISPLAY INVISIBLE (725 -50);
FORCEPROP 1 LASTPIN (625 -300) $PN 1
J 0
(615 -285);
DISPLAY 0.617021 (615 -285);
PAINT MONO (615 -285);
FORCEPROP 1 LASTPIN (825 -300) $PN 2
J 0
(810 -285);
DISPLAY 0.617021 (810 -285);
PAINT MONO (810 -285);
FORCEPROP 1 LAST VOLTAGE 25V
J 0
(975 -350);
DISPLAY 0.617021 (975 -350);
PAINT SKYBLUE (975 -350);
FORCEPROP 1 LAST MATERIAL X7R
J 0
(975 -400);
DISPLAY 0.617021 (975 -400);
PAINT SKYBLUE (975 -400);
FORCEPROP 1 LAST TOLERANCE 10%
J 2
(975 -400);
DISPLAY 0.617021 (975 -400);
PAINT SKYBLUE (975 -400);
FORCEPROP 1 LAST VALUE 0.22UF
J 2
(975 -350);
DISPLAY 0.617021 (975 -350);
PAINT SKYBLUE (975 -350);
FORCEPROP 1 LAST PACK_TYPE C0402
J 1
(975 -450);
DISPLAY 0.617021 (975 -450);
PAINT SKYBLUE (975 -450);
DISPLAY INVISIBLE (975 -450);
FORCEPROP 2 LAST CDS_LIB pure_quanta
J 0
(725 -300);
DISPLAY INVISIBLE (725 -300);
FORCEPROP 1 LAST PATH I48
J 0
(725 -100);
DISPLAY 0.978723 (725 -100);
PAINT WHITE (725 -100);
DISPLAY INVISIBLE (725 -100);
FORCEPROP 1 LAST PART_NUMBER CH4224K1B01
J 1
(800 -425);
DISPLAY 0.617021 (800 -425);
PAINT BLUE (800 -425);
DISPLAY INVISIBLE (800 -425);
FORCEADD Q_RES..1
(800 -100);
FORCEPROP 1 LAST LOCATION PR835
J 0
(575 -100);
DISPLAY 0.617021 (575 -100);
PAINT AQUA (575 -100);
FORCEPROP 0 LAST $SEC 1
J 0
(850 -100);
DISPLAY 0.680851 (850 -100);
PAINT MONO (850 -100);
DISPLAY INVISIBLE (850 -100);
FORCEPROP 0 LAST CDS_SEC 1
J 0
(850 -100);
DISPLAY 1.021277 (850 -100);
DISPLAY INVISIBLE (850 -100);
FORCEPROP 1 LASTPIN (700 -100) $PN 1
J 0
(712 -88);
DISPLAY 0.617021 (712 -88);
PAINT MONO (712 -88);
FORCEPROP 1 LASTPIN (900 -100) $PN 2
J 0
(862 -88);
DISPLAY 0.617021 (862 -88);
PAINT MONO (862 -88);
FORCEPROP 1 LAST WATTAGE 1/16W
J 2
(750 -200);
DISPLAY 0.617021 (750 -200);
PAINT SKYBLUE (750 -200);
FORCEPROP 1 LAST MATERIAL CHIP
J 0
(775 -200);
DISPLAY 0.617021 (775 -200);
PAINT SKYBLUE (775 -200);
FORCEPROP 1 LAST VALUE 0
J 2
(750 -150);
DISPLAY 0.617021 (750 -150);
PAINT SKYBLUE (750 -150);
FORCEPROP 1 LAST PACK_TYPE 0402LF
J 0
(850 -150);
DISPLAY 0.617021 (850 -150);
PAINT SKYBLUE (850 -150);
FORCEPROP 1 LAST TOLERANCE 5%
J 0
(775 -150);
DISPLAY 0.617021 (775 -150);
PAINT SKYBLUE (775 -150);
FORCEPROP 2 LAST CDS_LIB pure_quanta
J 0
(800 -100);
DISPLAY INVISIBLE (800 -100);
FORCEPROP 1 LAST PATH I49
J 0
(750 50);
DISPLAY 0.978723 (750 50);
PAINT WHITE (750 50);
DISPLAY INVISIBLE (750 50);
FORCEPROP 1 LAST PART_NUMBER CS00002JB13
J 0
(500 -150);
DISPLAY 0.617021 (500 -150);
PAINT BLUE (500 -150);
DISPLAY INVISIBLE (500 -150);
FORCEADD OFFPAGE..1
(-3375 -100);
FORCEPROP 2 LAST $XR1 85 
J 0
(-3717 -100);
DISPLAY 0.638298 (-3717 -100);
PAINT MONO (-3717 -100);
FORCEPROP 2 LAST $XR0 189 
J 0
(-3627 -100);
DISPLAY 0.638298 (-3627 -100);
PAINT MONO (-3627 -100);
FORCEPROP 2 LAST CDS_LIB standard
J 0
(-3375 -100);
DISPLAY INVISIBLE (-3375 -100);
FORCEPROP 1 LAST OFFPAGE TRUE
J 0
(-3050 -225);
DISPLAY 0.872340 (-3050 -225);
PAINT GREEN (-3050 -225);
DISPLAY INVISIBLE (-3050 -225);
FORCEPROP 1 LAST COMMENT_BODY TRUE
J 0
(-3250 -200);
DISPLAY 0.872340 (-3250 -200);
PAINT GREEN (-3250 -200);
DISPLAY INVISIBLE (-3250 -200);
FORCEPROP 2 LAST PATH I5
J 0
(-3625 -50);
DISPLAY 0.680851 (-3625 -50);
DISPLAY INVISIBLE (-3625 -50);
FORCEADD GND..1
(1200 -1750);
FORCEPROP 3 LASTPIN (1200 -1700) SIG_NAME GND\g
J 0
(1210 -1690);
DISPLAY 0.659574 (1210 -1690);
PAINT MONO (1210 -1690);
DISPLAY INVISIBLE (1210 -1690);
FORCEPROP 2 LAST CDS_LIB pure_quanta_power
J 0
(1200 -1750);
PAINT MONO (1200 -1750);
DISPLAY INVISIBLE (1200 -1750);
FORCEPROP 1 LAST SIZE 1B
J 0
(1275 -1800);
DISPLAY 0.872340 (1275 -1800);
PAINT AQUA (1275 -1800);
DISPLAY INVISIBLE (1275 -1800);
FORCEPROP 1 LAST HDL_POWER GND
J 0
(1200 -1600);
DISPLAY 0.872340 (1200 -1600);
PAINT GREEN (1200 -1600);
DISPLAY INVISIBLE (1200 -1600);
FORCEPROP 1 LAST PATH I50
J 0
(1275 -1750);
DISPLAY 0.872340 (1275 -1750);
PAINT AQUA (1275 -1750);
DISPLAY INVISIBLE (1275 -1750);
FORCEADD Q_RES..2
(1200 -1475);
FORCEPROP 1 LAST LOCATION PR830
J 0
(1250 -1350);
DISPLAY 0.617021 (1250 -1350);
PAINT AQUA (1250 -1350);
FORCEPROP 0 LAST $SEC 1
J 0
(1250 -1300);
DISPLAY 0.680851 (1250 -1300);
PAINT MONO (1250 -1300);
DISPLAY INVISIBLE (1250 -1300);
FORCEPROP 2 LAST CDS_SEC 1
J 0
(1250 -1250);
DISPLAY 1.021277 (1250 -1250);
DISPLAY INVISIBLE (1250 -1250);
FORCEPROP 1 LASTPIN (1200 -1375) $PN 1
J 0
(1205 -1413);
DISPLAY 0.617021 (1205 -1413);
PAINT MONO (1205 -1413);
FORCEPROP 1 LASTPIN (1200 -1575) $PN 2
J 0
(1205 -1565);
DISPLAY 0.617021 (1205 -1565);
PAINT MONO (1205 -1565);
FORCEPROP 1 LAST PACK_TYPE 0402LF
J 0
(1245 -1650);
DISPLAY 0.489362 (1245 -1650);
PAINT SKYBLUE (1245 -1650);
FORCEPROP 1 LAST MATERIAL CHIP
J 0
(1245 -1550);
DISPLAY 0.489362 (1245 -1550);
PAINT SKYBLUE (1245 -1550);
FORCEPROP 1 LAST WATTAGE 1/16W
J 0
(1245 -1500);
DISPLAY 0.489362 (1245 -1500);
PAINT SKYBLUE (1245 -1500);
FORCEPROP 1 LAST TOLERANCE 0.1%
J 0
(1250 -1450);
DISPLAY 0.489362 (1250 -1450);
PAINT SKYBLUE (1250 -1450);
FORCEPROP 1 LAST VALUE 15K
J 0
(1250 -1400);
DISPLAY 0.489362 (1250 -1400);
PAINT SKYBLUE (1250 -1400);
FORCEPROP 2 LAST CDS_LIB pure_quanta
J 0
(1200 -1475);
DISPLAY INVISIBLE (1200 -1475);
FORCEPROP 1 LAST PATH I51
J 0
(1250 -1300);
DISPLAY 0.978723 (1250 -1300);
PAINT WHITE (1250 -1300);
DISPLAY INVISIBLE (1250 -1300);
FORCEPROP 1 LAST PART_NUMBER CS31502BB03
J 0
(1245 -1600);
DISPLAY 0.489362 (1245 -1600);
PAINT BLUE (1245 -1600);
DISPLAY INVISIBLE (1245 -1600);
FORCEADD UNIVERSAL_POWER..1
(1075 -900);
FORCEPROP 3 LASTPIN (1075 -950) SIG_NAME P3V3_AUX\g
J 0
(1085 -940);
DISPLAY 0.659574 (1085 -940);
PAINT MONO (1085 -940);
DISPLAY INVISIBLE (1085 -940);
FORCEPROP 1 LAST HDL_POWER P3V3_AUX
J 1
(1075 -850);
DISPLAY 0.617021 (1075 -850);
PAINT GREEN (1075 -850);
FORCEPROP 2 LAST CDS_LIB pure_quanta_power
J 0
(1075 -900);
DISPLAY INVISIBLE (1075 -900);
FORCEPROP 1 LAST PATH I52
J 0
(1125 -875);
DISPLAY 0.872340 (1125 -875);
PAINT AQUA (1125 -875);
DISPLAY INVISIBLE (1125 -875);
FORCEADD Q_CAP..2
(2100 -1600);
FORCEPROP 1 LAST LOCATION PC569
J 1
(1925 -1600);
DISPLAY 0.617021 (1925 -1600);
PAINT AQUA (1925 -1600);
FORCEPROP 0 LAST $SEC 1
J 0
(2100 -1650);
DISPLAY 0.680851 (2100 -1650);
PAINT MONO (2100 -1650);
DISPLAY INVISIBLE (2100 -1650);
FORCEPROP 2 LAST CDS_SEC 1
J 0
(2100 -1350);
DISPLAY 1.021277 (2100 -1350);
DISPLAY INVISIBLE (2100 -1350);
FORCEPROP 1 LASTPIN (2000 -1600) $PN 1
J 0
(1990 -1585);
DISPLAY 0.617021 (1990 -1585);
PAINT MONO (1990 -1585);
FORCEPROP 1 LASTPIN (2200 -1600) $PN 2
J 0
(2185 -1585);
DISPLAY 0.617021 (2185 -1585);
PAINT MONO (2185 -1585);
FORCEPROP 1 LAST MATERIAL NPO
J 0
(2425 -1600);
DISPLAY 0.489362 (2425 -1600);
PAINT SKYBLUE (2425 -1600);
FORCEPROP 1 LAST TOLERANCE 1%
J 2
(2400 -1600);
DISPLAY 0.489362 (2400 -1600);
PAINT SKYBLUE (2400 -1600);
FORCEPROP 1 LAST VALUE 10PF
J 2
(2325 -1600);
DISPLAY 0.489362 (2325 -1600);
PAINT SKYBLUE (2325 -1600);
FORCEPROP 1 LAST VOLTAGE 50V
J 0
(2150 -1450);
DISPLAY 0.382979 (2150 -1450);
PAINT SKYBLUE (2150 -1450);
FORCEPROP 1 LAST PACK_TYPE 0402
J 1
(2050 -1450);
DISPLAY 0.382979 (2050 -1450);
PAINT SKYBLUE (2050 -1450);
FORCEPROP 2 LAST CDS_LIB pure_quanta
J 0
(2100 -1600);
DISPLAY INVISIBLE (2100 -1600);
FORCEPROP 1 LAST PATH I53
J 0
(2100 -1400);
DISPLAY 0.978723 (2100 -1400);
PAINT WHITE (2100 -1400);
DISPLAY INVISIBLE (2100 -1400);
FORCEPROP 1 LAST PART_NUMBER TMP_QCH0106F0B00
J 1
(2125 -1525);
DISPLAY 0.489362 (2125 -1525);
PAINT BLUE (2125 -1525);
DISPLAY INVISIBLE (2125 -1525);
FORCEADD Q_RES..1
(2100 -1300);
FORCEPROP 1 LAST LOCATION PR831
J 0
(2050 -1250);
DISPLAY 0.638298 (2050 -1250);
FORCEPROP 0 LAST $SEC 1
J 0
(2050 -1150);
DISPLAY 0.680851 (2050 -1150);
PAINT MONO (2050 -1150);
DISPLAY INVISIBLE (2050 -1150);
FORCEPROP 2 LAST CDS_SEC 1
J 0
(2050 -1100);
DISPLAY 1.021277 (2050 -1100);
DISPLAY INVISIBLE (2050 -1100);
FORCEPROP 1 LASTPIN (2000 -1300) $PN 1
J 0
(2012 -1288);
DISPLAY 0.787234 (2012 -1288);
PAINT MONO (2012 -1288);
DISPLAY INVISIBLE (2012 -1288);
FORCEPROP 1 LASTPIN (2200 -1300) $PN 2
J 0
(2162 -1288);
DISPLAY 0.787234 (2162 -1288);
PAINT MONO (2162 -1288);
DISPLAY INVISIBLE (2162 -1288);
FORCEPROP 1 LAST PACK_TYPE 0402LF
J 0
(2325 -1375);
DISPLAY 0.638298 (2325 -1375);
FORCEPROP 1 LAST TOLERANCE 0.1%
J 0
(2100 -1375);
DISPLAY 0.638298 (2100 -1375);
FORCEPROP 1 LAST VALUE 47K
J 2
(2075 -1375);
DISPLAY 0.638298 (2075 -1375);
FORCEPROP 1 LAST MATERIAL CHIP
J 0
(2100 -1425);
DISPLAY 0.638298 (2100 -1425);
FORCEPROP 1 LAST WATTAGE 1/16W
J 2
(2075 -1425);
DISPLAY 0.638298 (2075 -1425);
FORCEPROP 2 LAST CDS_LIB pure_quanta
J 0
(2100 -1300);
DISPLAY INVISIBLE (2100 -1300);
FORCEPROP 1 LAST PATH I54
J 0
(2050 -1150);
DISPLAY 0.978723 (2050 -1150);
PAINT WHITE (2050 -1150);
DISPLAY INVISIBLE (2050 -1150);
FORCEPROP 1 LAST PART_NUMBER CS34702BB05
J 0
(2225 -1275);
DISPLAY 0.638298 (2225 -1275);
DISPLAY INVISIBLE (2225 -1275);
FORCEADD Q_INDUCTOR..1
(1425 -475);
FORCEPROP 1 LAST LOCATION PL8066
J 0
(1300 -315);
DISPLAY 0.617021 (1300 -315);
PAINT AQUA (1300 -315);
FORCEPROP 0 LAST $SEC 1
J 0
(1300 -175);
DISPLAY 0.680851 (1300 -175);
PAINT MONO (1300 -175);
DISPLAY INVISIBLE (1300 -175);
FORCEPROP 2 LAST CDS_SEC 1
J 0
(1300 -175);
DISPLAY 1.021277 (1300 -175);
DISPLAY INVISIBLE (1300 -175);
FORCEPROP 0 LASTPIN (1325 -500) $PN 1
J 2
(1315 -490);
DISPLAY 0.617021 (1315 -490);
PAINT MONO (1315 -490);
FORCEPROP 0 LASTPIN (1525 -500) $PN 2
J 0
(1535 -490);
DISPLAY 0.617021 (1535 -490);
PAINT MONO (1535 -490);
FORCEPROP 1 LAST MATERIAL IND
J 0
(1300 -420);
DISPLAY 0.617021 (1300 -420);
PAINT SKYBLUE (1300 -420);
FORCEPROP 2 LAST PACK_TYPE SMLF
J 0
(1300 -225);
DISPLAY 0.617021 (1300 -225);
PAINT SKYBLUE (1300 -225);
FORCEPROP 2 LAST VALUE 1.5UH/53A
J 0
(1300 -275);
DISPLAY 0.617021 (1300 -275);
PAINT SKYBLUE (1300 -275);
FORCEPROP 1 LAST NEEDS_NO_SIZE TRUE
J 0
(1425 -475);
DISPLAY 0.468085 (1425 -475);
PAINT GREEN (1425 -475);
DISPLAY INVISIBLE (1425 -475);
FORCEPROP 2 LAST CDS_LIB pure_quanta
J 0
(1425 -475);
DISPLAY INVISIBLE (1425 -475);
FORCEPROP 1 LAST PATH I55
J 0
(1500 -420);
DISPLAY 0.723404 (1500 -420);
PAINT GREEN (1500 -420);
DISPLAY INVISIBLE (1500 -420);
FORCEPROP 1 LAST PART_NUMBER CV-15^0MZ02
J 0
(1300 -365);
DISPLAY 0.617021 (1300 -365);
PAINT BLUE (1300 -365);
DISPLAY INVISIBLE (1300 -365);
FORCEADD OFFPAGE..2
(2850 150);
FORCEPROP 2 LAST $XR2 270 
J 0
(3219 150);
DISPLAY 0.638298 (3219 150);
PAINT MONO (3219 150);
FORCEPROP 2 LAST $XR1 85 
J 0
(3129 150);
DISPLAY 0.638298 (3129 150);
PAINT MONO (3129 150);
FORCEPROP 2 LAST $XR0 81 
J 0
(3039 150);
DISPLAY 0.638298 (3039 150);
PAINT MONO (3039 150);
FORCEPROP 2 LAST CDS_LIB standard
J 0
(2850 150);
PAINT MONO (2850 150);
DISPLAY INVISIBLE (2850 150);
FORCEPROP 1 LAST OFFPAGE TRUE
J 0
(3175 25);
DISPLAY 0.872340 (3175 25);
PAINT GREEN (3175 25);
DISPLAY INVISIBLE (3175 25);
FORCEPROP 1 LAST COMMENT_BODY TRUE
J 0
(2805 55);
DISPLAY 0.872340 (2805 55);
PAINT GREEN (2805 55);
DISPLAY INVISIBLE (2805 55);
FORCEPROP 2 LAST PATH I56
J 0
(3300 200);
DISPLAY 0.680851 (3300 200);
DISPLAY INVISIBLE (3300 200);
FORCEADD Q_CAPP..1
(1650 -725);
FORCEPROP 1 LAST LOCATION PC1866
J 0
(1700 -625);
DISPLAY 0.638298 (1700 -625);
FORCEPROP 0 LAST $SEC 1
J 0
(1700 -575);
DISPLAY 0.680851 (1700 -575);
PAINT MONO (1700 -575);
DISPLAY INVISIBLE (1700 -575);
FORCEPROP 2 LAST CDS_SEC 1
J 0
(1700 -525);
DISPLAY 1.021277 (1700 -525);
DISPLAY INVISIBLE (1700 -525);
FORCEPROP 1 LASTPIN (1650 -625) $PN 1
J 0
(1660 -640);
DISPLAY 0.787234 (1660 -640);
PAINT MONO (1660 -640);
FORCEPROP 1 LASTPIN (1650 -825) $PN 2
J 0
(1660 -840);
DISPLAY 0.787234 (1660 -840);
PAINT MONO (1660 -840);
FORCEPROP 1 LAST PACK_TYPE THLF
J 0
(1700 -875);
DISPLAY 0.638298 (1700 -875);
FORCEPROP 1 LAST TOLERANCE 20%
J 0
(1700 -725);
DISPLAY 0.638298 (1700 -725);
FORCEPROP 1 LAST VOLTAGE 6.3V
J 0
(1700 -775);
DISPLAY 0.638298 (1700 -775);
FORCEPROP 1 LAST MATERIAL OSCON
J 0
(1700 -825);
DISPLAY 0.638298 (1700 -825);
FORCEPROP 1 LAST VALUE 560UF
J 0
(1700 -675);
DISPLAY 0.638298 (1700 -675);
FORCEPROP 2 LAST CDS_LIB pure_quanta
J 0
(1650 -725);
DISPLAY INVISIBLE (1650 -725);
FORCEPROP 1 LAST PATH I57
J 0
(1700 -575);
DISPLAY 0.978723 (1700 -575);
DISPLAY INVISIBLE (1700 -575);
FORCEPROP 1 LAST PART_NUMBER CC75601MD16
J 0
(1700 -925);
DISPLAY 0.638298 (1700 -925);
DISPLAY INVISIBLE (1700 -925);
FORCEADD Q_CAPP..1
(2100 -725);
FORCEPROP 1 LAST LOCATION PC1867
J 0
(2150 -625);
DISPLAY 0.638298 (2150 -625);
FORCEPROP 0 LAST $SEC 1
J 0
(2150 -575);
DISPLAY 0.680851 (2150 -575);
PAINT MONO (2150 -575);
DISPLAY INVISIBLE (2150 -575);
FORCEPROP 0 LAST CDS_SEC 1
J 0
(2150 -575);
DISPLAY 1.021277 (2150 -575);
DISPLAY INVISIBLE (2150 -575);
FORCEPROP 1 LASTPIN (2100 -625) $PN 1
J 0
(2110 -640);
DISPLAY 0.787234 (2110 -640);
PAINT MONO (2110 -640);
FORCEPROP 1 LASTPIN (2100 -825) $PN 2
J 0
(2110 -840);
DISPLAY 0.787234 (2110 -840);
PAINT MONO (2110 -840);
FORCEPROP 1 LAST MATERIAL OSCON
J 0
(2150 -825);
DISPLAY 0.638298 (2150 -825);
FORCEPROP 1 LAST VOLTAGE 6.3V
J 0
(2150 -775);
DISPLAY 0.638298 (2150 -775);
FORCEPROP 1 LAST VALUE 560UF
J 0
(2150 -675);
DISPLAY 0.638298 (2150 -675);
FORCEPROP 1 LAST PACK_TYPE THLF
J 0
(2150 -875);
DISPLAY 0.638298 (2150 -875);
FORCEPROP 1 LAST TOLERANCE 20%
J 0
(2150 -725);
DISPLAY 0.638298 (2150 -725);
FORCEPROP 2 LAST CDS_LIB pure_quanta
J 0
(2100 -725);
DISPLAY INVISIBLE (2100 -725);
FORCEPROP 1 LAST PATH I58
J 0
(2150 -575);
DISPLAY 0.978723 (2150 -575);
DISPLAY INVISIBLE (2150 -575);
FORCEPROP 1 LAST PART_NUMBER CC75601MD16
J 0
(2150 -925);
DISPLAY 0.638298 (2150 -925);
DISPLAY INVISIBLE (2150 -925);
FORCEADD Q_CAP..1
(2550 -700);
FORCEPROP 1 LAST LOCATION PC1868
J 0
(2625 -625);
DISPLAY 0.617021 (2625 -625);
PAINT AQUA (2625 -625);
FORCEPROP 0 LAST $SEC 1
J 0
(2600 -550);
DISPLAY 0.680851 (2600 -550);
PAINT MONO (2600 -550);
DISPLAY INVISIBLE (2600 -550);
FORCEPROP 0 LAST CDS_SEC 1
J 0
(2600 -550);
DISPLAY 0.680851 (2600 -550);
DISPLAY INVISIBLE (2600 -550);
FORCEPROP 1 LASTPIN (2550 -600) $PN 1
J 0
(2560 -620);
DISPLAY 0.617021 (2560 -620);
PAINT MONO (2560 -620);
FORCEPROP 1 LASTPIN (2550 -800) $PN 2
J 0
(2560 -820);
DISPLAY 0.617021 (2560 -820);
PAINT MONO (2560 -820);
FORCEPROP 1 LAST PACK_TYPE C0805
J 0
(2625 -925);
DISPLAY 0.617021 (2625 -925);
PAINT SKYBLUE (2625 -925);
FORCEPROP 1 LAST MATERIAL X6S
J 0
(2625 -825);
DISPLAY 0.617021 (2625 -825);
PAINT SKYBLUE (2625 -825);
FORCEPROP 1 LAST VOLTAGE 10V
J 0
(2625 -725);
DISPLAY 0.617021 (2625 -725);
PAINT SKYBLUE (2625 -725);
FORCEPROP 1 LAST VALUE 22UF
J 0
(2625 -675);
DISPLAY 0.617021 (2625 -675);
PAINT SKYBLUE (2625 -675);
FORCEPROP 1 LAST TOLERANCE 20%
J 0
(2625 -775);
DISPLAY 0.617021 (2625 -775);
PAINT SKYBLUE (2625 -775);
FORCEPROP 2 LAST CDS_LIB pure_quanta
J 0
(2550 -700);
DISPLAY INVISIBLE (2550 -700);
FORCEPROP 1 LAST PATH I59
J 0
(2600 -550);
DISPLAY 0.978723 (2600 -550);
PAINT WHITE (2600 -550);
DISPLAY INVISIBLE (2600 -550);
FORCEPROP 1 LAST PART_NUMBER CH6222MEA01
J 0
(2625 -875);
DISPLAY 0.617021 (2625 -875);
PAINT BLUE (2625 -875);
DISPLAY INVISIBLE (2625 -875);
FORCEADD P1V0_AUX..1
(-3300 -275);
FORCEPROP 3 LASTPIN (-3300 -325) SIG_NAME P12V_AUX\g
J 0
(-3290 -315);
DISPLAY 0.659574 (-3290 -315);
PAINT MONO (-3290 -315);
DISPLAY INVISIBLE (-3290 -315);
FORCEPROP 1 LAST HDL_POWER P12V_AUX
J 1
(-3289 -228);
DISPLAY 0.617021 (-3289 -228);
PAINT GREEN (-3289 -228);
FORCEPROP 2 LAST CDS_LIB pure_quanta_power
J 0
(-3300 -275);
DISPLAY INVISIBLE (-3300 -275);
FORCEPROP 1 LAST PATH I6
J 0
(-3250 -250);
DISPLAY 0.872340 (-3250 -250);
PAINT AQUA (-3250 -250);
DISPLAY INVISIBLE (-3250 -250);
FORCEADD Q_CAP..1
(2950 -725);
FORCEPROP 1 LAST LOCATION PC1599
J 0
(3000 -625);
DISPLAY 0.574468 (3000 -625);
PAINT AQUA (3000 -625);
FORCEPROP 0 LAST $SEC 1
J 0
(3000 -575);
DISPLAY 0.680851 (3000 -575);
PAINT MONO (3000 -575);
DISPLAY INVISIBLE (3000 -575);
FORCEPROP 0 LAST CDS_SEC 1
J 0
(3000 -575);
DISPLAY 1.021277 (3000 -575);
DISPLAY INVISIBLE (3000 -575);
FORCEPROP 1 LASTPIN (2950 -625) $PN 1
J 0
(2960 -645);
DISPLAY 0.617021 (2960 -645);
PAINT MONO (2960 -645);
FORCEPROP 1 LASTPIN (2950 -825) $PN 2
J 0
(2960 -845);
DISPLAY 0.617021 (2960 -845);
PAINT MONO (2960 -845);
FORCEPROP 1 LAST PACK_TYPE C0805
J 0
(3000 -925);
DISPLAY 0.617021 (3000 -925);
PAINT SKYBLUE (3000 -925);
FORCEPROP 1 LAST VOLTAGE 10V
J 0
(3000 -725);
DISPLAY 0.617021 (3000 -725);
PAINT SKYBLUE (3000 -725);
FORCEPROP 1 LAST VALUE 22UF
J 0
(3000 -675);
DISPLAY 0.617021 (3000 -675);
PAINT SKYBLUE (3000 -675);
FORCEPROP 1 LAST MATERIAL X6S
J 0
(3000 -825);
DISPLAY 0.617021 (3000 -825);
PAINT SKYBLUE (3000 -825);
FORCEPROP 1 LAST TOLERANCE 20%
J 0
(3000 -775);
DISPLAY 0.617021 (3000 -775);
PAINT SKYBLUE (3000 -775);
FORCEPROP 2 LAST CDS_LIB pure_quanta
J 0
(2950 -725);
DISPLAY INVISIBLE (2950 -725);
FORCEPROP 1 LAST PATH I60
J 0
(3000 -575);
DISPLAY 0.978723 (3000 -575);
PAINT WHITE (3000 -575);
DISPLAY INVISIBLE (3000 -575);
FORCEPROP 1 LAST PART_NUMBER CH6222MEA01
J 0
(3000 -875);
DISPLAY 0.617021 (3000 -875);
PAINT BLUE (3000 -875);
DISPLAY INVISIBLE (3000 -875);
FORCEADD GND..1
(3725 -1100);
FORCEPROP 3 LASTPIN (3725 -1050) SIG_NAME GND\g
J 0
(3735 -1040);
DISPLAY 0.659574 (3735 -1040);
PAINT MONO (3735 -1040);
DISPLAY INVISIBLE (3735 -1040);
FORCEPROP 2 LAST CDS_LIB pure_quanta_power
J 0
(3725 -1100);
PAINT MONO (3725 -1100);
DISPLAY INVISIBLE (3725 -1100);
FORCEPROP 1 LAST SIZE 1B
J 0
(3800 -1150);
DISPLAY 0.872340 (3800 -1150);
PAINT AQUA (3800 -1150);
DISPLAY INVISIBLE (3800 -1150);
FORCEPROP 1 LAST HDL_POWER GND
J 0
(3725 -950);
DISPLAY 0.872340 (3725 -950);
PAINT GREEN (3725 -950);
DISPLAY INVISIBLE (3725 -950);
FORCEPROP 1 LAST PATH I61
J 0
(3800 -1100);
DISPLAY 0.872340 (3800 -1100);
PAINT AQUA (3800 -1100);
DISPLAY INVISIBLE (3800 -1100);
FORCEADD Q_CAP..1
(3325 -725);
FORCEPROP 1 LAST LOCATION PC1600
J 0
(3375 -625);
DISPLAY 0.574468 (3375 -625);
PAINT AQUA (3375 -625);
FORCEPROP 0 LAST $SEC 1
J 0
(3375 -575);
DISPLAY 0.680851 (3375 -575);
PAINT MONO (3375 -575);
DISPLAY INVISIBLE (3375 -575);
FORCEPROP 0 LAST CDS_SEC 1
J 0
(3375 -575);
DISPLAY 1.021277 (3375 -575);
DISPLAY INVISIBLE (3375 -575);
FORCEPROP 1 LASTPIN (3325 -625) $PN 1
J 0
(3335 -645);
DISPLAY 0.617021 (3335 -645);
PAINT MONO (3335 -645);
FORCEPROP 1 LASTPIN (3325 -825) $PN 2
J 0
(3335 -845);
DISPLAY 0.617021 (3335 -845);
PAINT MONO (3335 -845);
FORCEPROP 1 LAST VALUE 22UF
J 0
(3375 -675);
DISPLAY 0.617021 (3375 -675);
PAINT SKYBLUE (3375 -675);
FORCEPROP 1 LAST PACK_TYPE C0805
J 0
(3375 -925);
DISPLAY 0.617021 (3375 -925);
PAINT SKYBLUE (3375 -925);
FORCEPROP 1 LAST MATERIAL X6S
J 0
(3375 -825);
DISPLAY 0.617021 (3375 -825);
PAINT SKYBLUE (3375 -825);
FORCEPROP 1 LAST TOLERANCE 20%
J 0
(3375 -775);
DISPLAY 0.617021 (3375 -775);
PAINT SKYBLUE (3375 -775);
FORCEPROP 1 LAST VOLTAGE 10V
J 0
(3375 -725);
DISPLAY 0.617021 (3375 -725);
PAINT SKYBLUE (3375 -725);
FORCEPROP 2 LAST CDS_LIB pure_quanta
J 0
(3325 -725);
DISPLAY INVISIBLE (3325 -725);
FORCEPROP 1 LAST PATH I62
J 0
(3375 -575);
DISPLAY 0.978723 (3375 -575);
PAINT WHITE (3375 -575);
DISPLAY INVISIBLE (3375 -575);
FORCEPROP 1 LAST PART_NUMBER CH6222MEA01
J 0
(3375 -875);
DISPLAY 0.617021 (3375 -875);
PAINT BLUE (3375 -875);
DISPLAY INVISIBLE (3375 -875);
FORCEADD Q_CAP..1
(3725 -725);
FORCEPROP 1 LAST LOCATION PC1869
J 0
(3775 -625);
DISPLAY 0.617021 (3775 -625);
PAINT AQUA (3775 -625);
FORCEPROP 2 LAST $SEC 1
J 0
(3775 -525);
DISPLAY 0.680851 (3775 -525);
PAINT MONO (3775 -525);
DISPLAY INVISIBLE (3775 -525);
FORCEPROP 2 LAST CDS_SEC 1
J 0
(3775 -525);
DISPLAY 1.021277 (3775 -525);
DISPLAY INVISIBLE (3775 -525);
FORCEPROP 1 LASTPIN (3725 -625) $PN 1
J 0
(3735 -645);
DISPLAY 0.617021 (3735 -645);
FORCEPROP 1 LASTPIN (3725 -825) $PN 2
J 0
(3735 -845);
DISPLAY 0.617021 (3735 -845);
FORCEPROP 1 LAST PACK_TYPE 0402
J 0
(3775 -925);
DISPLAY 0.617021 (3775 -925);
PAINT SKYBLUE (3775 -925);
FORCEPROP 1 LAST VOLTAGE 25V
J 0
(3775 -725);
DISPLAY 0.617021 (3775 -725);
PAINT SKYBLUE (3775 -725);
FORCEPROP 1 LAST MATERIAL X7R
J 0
(3775 -825);
DISPLAY 0.617021 (3775 -825);
PAINT SKYBLUE (3775 -825);
FORCEPROP 1 LAST VALUE 0.1UF
J 0
(3775 -675);
DISPLAY 0.617021 (3775 -675);
PAINT SKYBLUE (3775 -675);
FORCEPROP 1 LAST TOLERANCE 10%
J 0
(3775 -775);
DISPLAY 0.617021 (3775 -775);
PAINT SKYBLUE (3775 -775);
FORCEPROP 2 LAST CDS_LIB pure_quanta
J 0
(3725 -725);
PAINT MONO (3725 -725);
DISPLAY INVISIBLE (3725 -725);
FORCEPROP 1 LAST PATH I63
J 0
(3775 -575);
DISPLAY 0.978723 (3775 -575);
PAINT WHITE (3775 -575);
DISPLAY INVISIBLE (3775 -575);
FORCEPROP 1 LAST PART_NUMBER CH4104K1B00
J 0
(3775 -875);
DISPLAY 0.617021 (3775 -875);
PAINT BLUE (3775 -875);
DISPLAY INVISIBLE (3775 -875);
FORCEADD UNIVERSAL_POWER..1
(4175 -200);
FORCEPROP 3 LASTPIN (4175 -250) SIG_NAME P3V3_AUX\g
J 0
(4185 -240);
DISPLAY 0.659574 (4185 -240);
PAINT MONO (4185 -240);
DISPLAY INVISIBLE (4185 -240);
FORCEPROP 1 LAST HDL_POWER P3V3_AUX
J 1
(4175 -150);
DISPLAY 0.617021 (4175 -150);
PAINT GREEN (4175 -150);
FORCEPROP 2 LAST CDS_LIB pure_quanta_power
J 0
(4175 -200);
PAINT MONO (4175 -200);
DISPLAY INVISIBLE (4175 -200);
FORCEPROP 1 LAST PATH I64
J 0
(4225 -175);
DISPLAY 0.872340 (4225 -175);
PAINT AQUA (4225 -175);
DISPLAY INVISIBLE (4225 -175);
FORCEADD Q_RES..2
(900 450);
FORCEPROP 1 LAST LOCATION PR8073
J 0
(945 575);
DISPLAY 0.617021 (945 575);
PAINT SKYBLUE (945 575);
FORCEPROP 2 LAST $SEC 1
J 0
(950 675);
DISPLAY 0.680851 (950 675);
PAINT MONO (950 675);
DISPLAY INVISIBLE (950 675);
FORCEPROP 2 LAST CDS_SEC 1
J 0
(950 675);
DISPLAY 1.021277 (950 675);
DISPLAY INVISIBLE (950 675);
FORCEPROP 1 LASTPIN (900 550) $PN 1
J 0
(905 512);
DISPLAY 0.617021 (905 512);
FORCEPROP 1 LASTPIN (900 350) $PN 2
J 0
(905 360);
DISPLAY 0.617021 (905 360);
FORCEPROP 1 LAST MATERIAL CHIP
J 0
(940 375);
DISPLAY 0.617021 (940 375);
PAINT SKYBLUE (940 375);
FORCEPROP 1 LAST PACK_TYPE 0402LF
J 0
(940 325);
DISPLAY 0.617021 (940 325);
PAINT SKYBLUE (940 325);
FORCEPROP 1 LAST WATTAGE 1/16W
J 0
(940 425);
DISPLAY 0.617021 (940 425);
PAINT SKYBLUE (940 425);
FORCEPROP 1 LAST TOLERANCE 1%
J 0
(945 475);
DISPLAY 0.617021 (945 475);
PAINT SKYBLUE (945 475);
FORCEPROP 1 LAST VALUE 1K
J 0
(945 525);
DISPLAY 0.617021 (945 525);
PAINT SKYBLUE (945 525);
FORCEPROP 2 LAST CDS_LIB pure_quanta
J 0
(900 450);
PAINT MONO (900 450);
DISPLAY INVISIBLE (900 450);
FORCEPROP 1 LAST PATH I65
J 0
(950 625);
DISPLAY 0.978723 (950 625);
PAINT WHITE (950 625);
DISPLAY INVISIBLE (950 625);
FORCEPROP 1 LAST PART_NUMBER CS21002FB06
J 0
(940 275);
DISPLAY 0.617021 (940 275);
PAINT SKYBLUE (940 275);
DISPLAY INVISIBLE (940 275);
FORCEADD UNIVERSAL_POWER..1
(900 675);
FORCEPROP 3 LASTPIN (900 625) SIG_NAME P3V3_AUX\g
J 0
(910 635);
DISPLAY 0.659574 (910 635);
PAINT MONO (910 635);
DISPLAY INVISIBLE (910 635);
FORCEPROP 1 LAST HDL_POWER P3V3_AUX
J 1
(900 725);
DISPLAY 0.617021 (900 725);
PAINT GREEN (900 725);
FORCEPROP 2 LAST CDS_LIB pure_quanta_power
J 0
(900 675);
DISPLAY INVISIBLE (900 675);
FORCEPROP 1 LAST PATH I66
J 0
(950 700);
DISPLAY 0.872340 (950 700);
PAINT AQUA (950 700);
DISPLAY INVISIBLE (950 700);
FORCEADD Q_RES..1
(1425 150);
FORCEPROP 1 LAST LOCATION R6099
J 0
(1200 150);
DISPLAY 0.617021 (1200 150);
PAINT AQUA (1200 150);
FORCEPROP 0 LAST $SEC 1
J 0
(1475 150);
DISPLAY 0.680851 (1475 150);
PAINT MONO (1475 150);
DISPLAY INVISIBLE (1475 150);
FORCEPROP 0 LAST CDS_SEC 1
J 0
(1475 150);
DISPLAY 1.021277 (1475 150);
DISPLAY INVISIBLE (1475 150);
FORCEPROP 1 LASTPIN (1325 150) $PN 1
J 0
(1337 162);
DISPLAY 0.617021 (1337 162);
PAINT MONO (1337 162);
FORCEPROP 1 LASTPIN (1525 150) $PN 2
J 0
(1487 162);
DISPLAY 0.617021 (1487 162);
PAINT MONO (1487 162);
FORCEPROP 1 LAST WATTAGE 1/16W
J 2
(1375 50);
DISPLAY 0.617021 (1375 50);
PAINT SKYBLUE (1375 50);
FORCEPROP 1 LAST VALUE 0
J 2
(1375 100);
DISPLAY 0.617021 (1375 100);
PAINT SKYBLUE (1375 100);
FORCEPROP 1 LAST TOLERANCE 5%
J 0
(1400 100);
DISPLAY 0.617021 (1400 100);
PAINT SKYBLUE (1400 100);
FORCEPROP 1 LAST MATERIAL CHIP
J 0
(1400 50);
DISPLAY 0.617021 (1400 50);
PAINT SKYBLUE (1400 50);
FORCEPROP 1 LAST PACK_TYPE 0402LF
J 0
(1475 100);
DISPLAY 0.617021 (1475 100);
PAINT SKYBLUE (1475 100);
FORCEPROP 2 LAST CDS_LIB pure_quanta
J 0
(1425 150);
DISPLAY INVISIBLE (1425 150);
FORCEPROP 1 LAST PATH I67
J 0
(1375 300);
DISPLAY 0.978723 (1375 300);
PAINT WHITE (1375 300);
DISPLAY INVISIBLE (1375 300);
FORCEPROP 1 LAST PART_NUMBER CS00002JB13
J 0
(1125 100);
DISPLAY 0.617021 (1125 100);
PAINT BLUE (1125 100);
DISPLAY INVISIBLE (1125 100);
FORCEADD Q_CAP..1
(2625 -75);
FORCEPROP 1 LAST LOCATION C5015
J 0
(2675 25);
DISPLAY 0.638298 (2675 25);
FORCEPROP 0 LAST $SEC 1
J 0
(2675 75);
DISPLAY 0.680851 (2675 75);
PAINT MONO (2675 75);
DISPLAY INVISIBLE (2675 75);
FORCEPROP 0 LAST CDS_SEC 1
J 0
(2675 75);
DISPLAY 0.680851 (2675 75);
DISPLAY INVISIBLE (2675 75);
FORCEPROP 1 LASTPIN (2625 25) $PN 1
J 0
(2635 5);
DISPLAY 0.787234 (2635 5);
PAINT MONO (2635 5);
FORCEPROP 1 LASTPIN (2625 -175) $PN 2
J 0
(2635 -195);
DISPLAY 0.787234 (2635 -195);
PAINT MONO (2635 -195);
FORCEPROP 1 LAST MATERIAL EMPTY
J 0
(2675 -175);
DISPLAY 0.638298 (2675 -175);
FORCEPROP 1 LAST VALUE 1000PF
J 0
(2675 -25);
DISPLAY 0.638298 (2675 -25);
FORCEPROP 1 LAST VOLTAGE 50V
J 0
(2675 -75);
DISPLAY 0.638298 (2675 -75);
FORCEPROP 1 LAST TOLERANCE 5%
J 0
(2675 -125);
DISPLAY 0.638298 (2675 -125);
FORCEPROP 1 LAST PACK_TYPE 0402
J 0
(2675 -275);
DISPLAY 0.638298 (2675 -275);
FORCEPROP 2 LAST CDS_LIB pure_quanta
J 0
(2625 -75);
DISPLAY INVISIBLE (2625 -75);
FORCEPROP 1 LAST PATH I68
J 0
(2675 75);
DISPLAY 0.978723 (2675 75);
PAINT WHITE (2675 75);
DISPLAY INVISIBLE (2675 75);
FORCEPROP 1 LAST PART_NUMBER TMP_QCH21006JB10
J 0
(2675 -225);
DISPLAY 0.638298 (2675 -225);
DISPLAY INVISIBLE (2675 -225);
FORCEADD GND..1
(2625 -325);
FORCEPROP 3 LASTPIN (2625 -275) SIG_NAME GND\g
J 0
(2635 -265);
DISPLAY 0.659574 (2635 -265);
PAINT MONO (2635 -265);
DISPLAY INVISIBLE (2635 -265);
FORCEPROP 1 LAST SIZE 1B
J 0
(2700 -375);
DISPLAY 0.872340 (2700 -375);
PAINT AQUA (2700 -375);
DISPLAY INVISIBLE (2700 -375);
FORCEPROP 2 LAST CDS_LIB pure_quanta_power
J 0
(2625 -325);
PAINT MONO (2625 -325);
DISPLAY INVISIBLE (2625 -325);
FORCEPROP 1 LAST HDL_POWER GND
J 0
(2625 -175);
DISPLAY 0.872340 (2625 -175);
PAINT GREEN (2625 -175);
DISPLAY INVISIBLE (2625 -175);
FORCEPROP 1 LAST PATH I69
J 0
(2700 -325);
DISPLAY 0.872340 (2700 -325);
PAINT AQUA (2700 -325);
DISPLAY INVISIBLE (2700 -325);
FORCEADD GND..1
(-2700 -1475);
FORCEPROP 3 LASTPIN (-2700 -1425) SIG_NAME GND\g
J 0
(-2690 -1415);
DISPLAY 0.659574 (-2690 -1415);
PAINT MONO (-2690 -1415);
DISPLAY INVISIBLE (-2690 -1415);
FORCEPROP 1 LAST SIZE 1B
J 0
(-2625 -1525);
DISPLAY 0.872340 (-2625 -1525);
PAINT AQUA (-2625 -1525);
DISPLAY INVISIBLE (-2625 -1525);
FORCEPROP 2 LAST CDS_LIB pure_quanta_power
J 0
(-2700 -1475);
DISPLAY INVISIBLE (-2700 -1475);
FORCEPROP 1 LAST HDL_POWER GND
J 0
(-2700 -1325);
DISPLAY 0.872340 (-2700 -1325);
PAINT GREEN (-2700 -1325);
DISPLAY INVISIBLE (-2700 -1325);
FORCEPROP 1 LAST PATH I7
J 0
(-2625 -1475);
DISPLAY 0.872340 (-2625 -1475);
PAINT AQUA (-2625 -1475);
DISPLAY INVISIBLE (-2625 -1475);
FORCEADD Q_CAP..1
(-1825 425);
FORCEPROP 1 LAST LOCATION PC8013
J 0
(-1775 525);
DISPLAY 0.489362 (-1775 525);
PAINT AQUA (-1775 525);
FORCEPROP 0 LAST $SEC 1
J 0
(-1775 550);
DISPLAY 0.680851 (-1775 550);
PAINT MONO (-1775 550);
DISPLAY INVISIBLE (-1775 550);
FORCEPROP 0 LAST CDS_SEC 1
J 0
(-1775 550);
DISPLAY 0.680851 (-1775 550);
DISPLAY INVISIBLE (-1775 550);
FORCEPROP 1 LASTPIN (-1825 525) $PN 1
J 0
(-1815 505);
DISPLAY 0.787234 (-1815 505);
PAINT MONO (-1815 505);
FORCEPROP 1 LASTPIN (-1825 325) $PN 2
J 0
(-1815 305);
DISPLAY 0.787234 (-1815 305);
PAINT MONO (-1815 305);
FORCEPROP 1 LAST TOLERANCE 20%
J 0
(-1775 375);
DISPLAY 0.382979 (-1775 375);
PAINT SKYBLUE (-1775 375);
FORCEPROP 1 LAST MATERIAL X6S
J 0
(-1775 325);
DISPLAY 0.382979 (-1775 325);
PAINT SKYBLUE (-1775 325);
FORCEPROP 1 LAST VOLTAGE 16V
J 0
(-1775 425);
DISPLAY 0.382979 (-1775 425);
PAINT SKYBLUE (-1775 425);
FORCEPROP 1 LAST VALUE 22UF
J 0
(-1775 475);
DISPLAY 0.382979 (-1775 475);
PAINT SKYBLUE (-1775 475);
FORCEPROP 1 LAST PACK_TYPE C0805
J 0
(-1775 225);
DISPLAY 0.382979 (-1775 225);
PAINT SKYBLUE (-1775 225);
FORCEPROP 2 LAST CDS_LIB pure_quanta
J 0
(-1825 425);
DISPLAY INVISIBLE (-1825 425);
FORCEPROP 1 LAST PATH I70
J 0
(-1775 575);
DISPLAY 0.978723 (-1775 575);
PAINT WHITE (-1775 575);
DISPLAY INVISIBLE (-1775 575);
FORCEPROP 1 LAST PART_NUMBER CH6223MEA01
J 0
(-1775 275);
DISPLAY 0.297872 (-1775 275);
PAINT SKYBLUE (-1775 275);
DISPLAY INVISIBLE (-1775 275);
FORCEADD Q_CAP..1
(-1625 450);
FORCEPROP 1 LAST LOCATION PC8014
J 0
(-1575 550);
DISPLAY 0.489362 (-1575 550);
PAINT AQUA (-1575 550);
FORCEPROP 0 LAST $SEC 1
J 0
(-1575 575);
DISPLAY 0.680851 (-1575 575);
PAINT MONO (-1575 575);
DISPLAY INVISIBLE (-1575 575);
FORCEPROP 0 LAST CDS_SEC 1
J 0
(-1575 575);
DISPLAY 0.680851 (-1575 575);
DISPLAY INVISIBLE (-1575 575);
FORCEPROP 1 LASTPIN (-1625 550) $PN 1
J 0
(-1615 530);
DISPLAY 0.787234 (-1615 530);
PAINT MONO (-1615 530);
FORCEPROP 1 LASTPIN (-1625 350) $PN 2
J 0
(-1615 330);
DISPLAY 0.787234 (-1615 330);
PAINT MONO (-1615 330);
FORCEPROP 1 LAST MATERIAL X6S
J 0
(-1575 350);
DISPLAY 0.382979 (-1575 350);
PAINT SKYBLUE (-1575 350);
FORCEPROP 1 LAST VALUE 22UF
J 0
(-1575 500);
DISPLAY 0.382979 (-1575 500);
PAINT SKYBLUE (-1575 500);
FORCEPROP 1 LAST VOLTAGE 16V
J 0
(-1575 450);
DISPLAY 0.382979 (-1575 450);
PAINT SKYBLUE (-1575 450);
FORCEPROP 1 LAST TOLERANCE 20%
J 0
(-1575 400);
DISPLAY 0.382979 (-1575 400);
PAINT SKYBLUE (-1575 400);
FORCEPROP 1 LAST PACK_TYPE C0805
J 0
(-1575 250);
DISPLAY 0.382979 (-1575 250);
PAINT SKYBLUE (-1575 250);
FORCEPROP 2 LAST CDS_LIB pure_quanta
J 0
(-1625 450);
DISPLAY INVISIBLE (-1625 450);
FORCEPROP 1 LAST PATH I71
J 0
(-1575 600);
DISPLAY 0.978723 (-1575 600);
PAINT WHITE (-1575 600);
DISPLAY INVISIBLE (-1575 600);
FORCEPROP 1 LAST PART_NUMBER CH6223MEA01
J 0
(-1575 300);
DISPLAY 0.489362 (-1575 300);
PAINT SKYBLUE (-1575 300);
DISPLAY INVISIBLE (-1575 300);
FORCEADD Q_CAP..1
R 2
(-2700 -1175);
FORCEPROP 1 LAST LOCATION PC1870
J 2
(-2525 -1050);
DISPLAY 0.617021 (-2525 -1050);
PAINT AQUA (-2525 -1050);
FORCEPROP 0 LAST $SEC 1
J 0
(-2750 -1025);
DISPLAY 0.680851 (-2750 -1025);
PAINT MONO (-2750 -1025);
DISPLAY INVISIBLE (-2750 -1025);
FORCEPROP 0 LAST CDS_SEC 1
J 0
(-2750 -1025);
DISPLAY 0.680851 (-2750 -1025);
DISPLAY INVISIBLE (-2750 -1025);
FORCEPROP 1 LASTPIN (-2700 -1075) $PN 1
J 2
(-2710 -1095);
DISPLAY 0.617021 (-2710 -1095);
PAINT MONO (-2710 -1095);
FORCEPROP 1 LASTPIN (-2700 -1275) $PN 2
J 2
(-2710 -1295);
DISPLAY 0.617021 (-2710 -1295);
PAINT MONO (-2710 -1295);
FORCEPROP 1 LAST VALUE 0.1UF
J 0
(-2645 -1097);
DISPLAY 0.617021 (-2645 -1097);
PAINT SKYBLUE (-2645 -1097);
FORCEPROP 1 LAST VOLTAGE 25V
J 0
(-2645 -1146);
DISPLAY 0.617021 (-2645 -1146);
PAINT SKYBLUE (-2645 -1146);
FORCEPROP 1 LAST PACK_TYPE 0402
J 0
(-2645 -1293);
DISPLAY 0.617021 (-2645 -1293);
PAINT SKYBLUE (-2645 -1293);
FORCEPROP 1 LAST TOLERANCE 10%
J 0
(-2645 -1195);
DISPLAY 0.617021 (-2645 -1195);
PAINT SKYBLUE (-2645 -1195);
FORCEPROP 1 LAST MATERIAL EMPTY
J 0
(-2645 -1244);
DISPLAY 0.617021 (-2645 -1244);
PAINT RED (-2645 -1244);
FORCEPROP 2 LAST CDS_LIB pure_quanta
J 0
(-2700 -1175);
DISPLAY INVISIBLE (-2700 -1175);
FORCEPROP 1 LAST PATH I8
J 2
(-2750 -1025);
DISPLAY 0.978723 (-2750 -1025);
PAINT WHITE (-2750 -1025);
DISPLAY INVISIBLE (-2750 -1025);
FORCEPROP 1 LAST PART_NUMBER CH4104K1B00
J 0
(-2645 -1342);
DISPLAY 0.617021 (-2645 -1342);
PAINT BLUE (-2645 -1342);
DISPLAY INVISIBLE (-2645 -1342);
FORCEADD GND..1
(-2150 -1150);
FORCEPROP 3 LASTPIN (-2150 -1100) SIG_NAME GND\g
J 0
(-2140 -1090);
DISPLAY 0.659574 (-2140 -1090);
PAINT MONO (-2140 -1090);
DISPLAY INVISIBLE (-2140 -1090);
FORCEPROP 1 LAST SIZE 1B
J 0
(-2075 -1200);
DISPLAY 0.872340 (-2075 -1200);
PAINT AQUA (-2075 -1200);
DISPLAY INVISIBLE (-2075 -1200);
FORCEPROP 2 LAST CDS_LIB pure_quanta_power
J 0
(-2150 -1150);
DISPLAY INVISIBLE (-2150 -1150);
FORCEPROP 1 LAST HDL_POWER GND
J 0
(-2150 -1000);
DISPLAY 0.872340 (-2150 -1000);
PAINT GREEN (-2150 -1000);
DISPLAY INVISIBLE (-2150 -1000);
FORCEPROP 1 LAST PATH I9
J 0
(-2075 -1150);
DISPLAY 0.872340 (-2075 -1150);
PAINT AQUA (-2075 -1150);
DISPLAY INVISIBLE (-2075 -1150);
FORCEADD DNS..1
(-3250 -625);
PAINT RED (-3250 -625);
FORCEPROP 2 LAST CDS_LIB mstr_misc
J 0
(-3250 -625);
DISPLAY INVISIBLE (-3250 -625);
FORCEPROP 1 LAST COMMENT_BODY TRUE
J 0
(-3250 -625);
DISPLAY INVISIBLE (-3250 -625);
FORCEADD DNS..1
(-1775 -1100);
PAINT RED (-1775 -1100);
FORCEPROP 2 LAST CDS_LIB mstr_misc
J 0
(-1775 -1100);
DISPLAY INVISIBLE (-1775 -1100);
FORCEPROP 1 LAST COMMENT_BODY TRUE
J 0
(-1775 -1100);
DISPLAY INVISIBLE (-1775 -1100);
FORCEADD QUANTA_TITLE_BLOCK_C..1
(4525 -3325);
FORCEPROP 0 LAST CDS_CON_LAST_MODIFIED Thu Sep 14 16:12:22 2023
J 0
(2640 -3310);
DISPLAY INVISIBLE (2640 -3310);
FORCEPROP 1 LAST CUSTOM_TXT_CDS <CON_LAST_MODIFIED>
J 0
(2640 -3310);
DISPLAY 0.978723 (2640 -3310);
FORCEPROP 2 LAST CUSTOM_TXT_CDS <XR_PAGE_TITLE>
J 0
(-3365 1925);
DISPLAY 0.638298 (-3365 1925);
PAINT PINK (-3365 1925);
DISPLAY INVISIBLE (-3365 1925);
FORCEPROP 1 LAST CUSTOM_TXT_CDS <NAME_2>
J 0
(1350 -3275);
FORCEPROP 1 LAST CUSTOM_TXT_CDS <NAME_1>
J 0
(1350 -3150);
FORCEPROP 1 LAST CUSTOM_TXT_CDS <Q_NUMBER>
J 0
(3122 -3222);
DISPLAY 1.212766 (3122 -3222);
FORCEPROP 1 LAST CUSTOM_TXT_CDS <Q_PROJ>
J 0
(2143 -3223);
DISPLAY 1.212766 (2143 -3223);
FORCEPROP 1 LAST CUSTOM_TXT_CDS <Q_REV>
J 0
(4341 -3222);
DISPLAY 1.212766 (4341 -3222);
FORCEPROP 1 LAST CUSTOM_TXT_CDS <CON_PAGE_NUM> OF <CON_TOTAL_PAGES>
J 0
(4079 -3307);
DISPLAY 0.978723 (4079 -3307);
FORCEPROP 1 LAST Q_TITLE NCP3284/P3V3_AUX
J 0
(-4750 -3275);
DISPLAY 2.446809 (-4750 -3275);
PAINT GREEN (-4750 -3275);
FORCEPROP 2 LAST PAGE_BORDER TRUE
J 0
(-3365 1925);
DISPLAY 0.638298 (-3365 1925);
PAINT PINK (-3365 1925);
DISPLAY INVISIBLE (-3365 1925);
FORCEPROP 1 LAST CDS_LMAN_SYM_OUTLINE -9475,6775,100,-125
J 0
(4525 -3325);
DISPLAY 0.468085 (4525 -3325);
PAINT GREEN (4525 -3325);
DISPLAY INVISIBLE (4525 -3325);
FORCEPROP 2 LAST CDS_LIB pure_quanta
J 0
(4525 -3325);
DISPLAY INVISIBLE (4525 -3325);
FORCEPROP 2 LAST CDS_XR_PAGE_TITLE CR-190 : @T6G_MB_LIB.T6G(SCH_1):PAGE190
J 0
(-3365 1925);
DISPLAY 0.638298 (-3365 1925);
PAINT PINK (-3365 1925);
DISPLAY INVISIBLE (-3365 1925);
FORCEPROP 1 LAST Q_DEPT BU9
J 1
(750 -3275);
DISPLAY 1.957447 (750 -3275);
PAINT GREEN (750 -3275);
DISPLAY INVISIBLE (750 -3275);
FORCEPROP 1 LAST COMMENT_BODY TRUE
J 0
(4537 -3338);
DISPLAY 0.978723 (4537 -3338);
PAINT GREEN (4537 -3338);
DISPLAY INVISIBLE (4537 -3338);
FORCEADD DNS..1
(-2600 -1250);
PAINT RED (-2600 -1250);
FORCEPROP 2 LAST CDS_LIB mstr_misc
J 0
(-2600 -1250);
DISPLAY INVISIBLE (-2600 -1250);
FORCEPROP 1 LAST COMMENT_BODY TRUE
J 0
(-2600 -1250);
DISPLAY INVISIBLE (-2600 -1250);
FORCEADD DNS..1
(2550 -75);
PAINT RED (2550 -75);
FORCEPROP 2 LAST CDS_LIB mstr_misc
J 0
(2550 -75);
DISPLAY INVISIBLE (2550 -75);
FORCEPROP 1 LAST COMMENT_BODY TRUE
J 0
(2550 -75);
DISPLAY INVISIBLE (2550 -75);
FORCEADD DNS..1
(-3250 -1200);
PAINT RED (-3250 -1200);
FORCEPROP 2 LAST CDS_LIB mstr_misc
J 0
(-3250 -1200);
DISPLAY INVISIBLE (-3250 -1200);
FORCEPROP 1 LAST COMMENT_BODY TRUE
J 0
(-3250 -1200);
DISPLAY INVISIBLE (-3250 -1200);
WIRE 16 -1 (-3300 -1425)(-3300 -1275);
WIRE 16 -1 (-2050 -550)(-2050 -475);
WIRE 16 -1 (-1750 -1175)(-1750 -1225);
WIRE 16 -1 (-1350 -1325)(-1350 -1275);
WIRE 16 -1 (-1625 -550)(-1625 -475);
WIRE 16 -1 (-4525 900)(-4525 1000);
WIRE 16 -1 (-4400 1300)(-4525 1300);
WIRE 16 -1 (-4525 1300)(-4525 1675);
WIRE 16 -1 (-4525 1200)(-4525 1300);
WIRE 16 -1 (-900 625)(-900 500);
WIRE 16 -1 (300 -950)(500 -950);
WIRE 16 -1 (1200 -1700)(1200 -1575);
WIRE 16 -1 (925 -1000)(1075 -1000);
WIRE 16 -1 (1075 -1000)(1075 -950);
WIRE 16 -1 (-3300 -500)(-3300 -325);
WIRE 16 -1 (900 625)(900 550);
WIRE 16 -1 (2625 -175)(2625 -275);
WIRE 16 -1 (-2700 -1425)(-2700 -1275);
WIRE 16 -1 (-2150 -1100)(-2150 -1075);
WIRE 16 2175 (-4450 -2125)(-2625 -2125);
WIRE 16 2175 (-4450 -2125)(-4450 -2425);
WIRE 16 2175 (-2625 -2125)(-2625 -2425);
WIRE 16 2175 (-4450 -2425)(-2625 -2425);
WIRE 16 -1 (1325 150)(900 150);
WIRE 16 -1 (900 150)(900 350);
WIRE 16 -1 (300 150)(900 150);
FORCEPROP 2 LAST SIG_NAME PWRGD_P3V3_AUX_R1
J 0
(440 160);
DISPLAY 0.617021 (440 160);
FORCEPROP 2 LASTPROP $XRERR UNIQUE?
J 0
(200 160);
DISPLAY 0.638298 (200 160);
PAINT MONO (200 160);
DISPLAY INVISIBLE (200 160);
WIRE 16 -1 (-1750 -850)(-550 -850);
FORCEPROP 2 LAST SIG_NAME P3V3_AUX_SS
J 0
(-1085 -840);
DISPLAY 0.617021 (-1085 -840);
FORCEPROP 2 LASTPROP $XRERR UNIQUE?
J 0
(-1325 -840);
DISPLAY 0.638298 (-1325 -840);
PAINT MONO (-1325 -840);
DISPLAY INVISIBLE (-1325 -840);
WIRE 16 -1 (-1750 -975)(-1750 -850);
WIRE 16 -1 (725 -1000)(300 -1000);
FORCEPROP 2 LAST SIG_NAME P3V3_AUX_VOS
J 0
(440 -1040);
DISPLAY 0.617021 (440 -1040);
FORCEPROP 2 LASTPROP $XRERR UNIQUE?
J 0
(200 -1040);
DISPLAY 0.638298 (200 -1040);
PAINT MONO (200 -1040);
DISPLAY INVISIBLE (200 -1040);
WIRE 16 -1 (-550 -1150)(-1075 -1150);
FORCEPROP 2 LAST SIG_NAME NC_PU9_2
J 0
(-1085 -1140);
DISPLAY 0.617021 (-1085 -1140);
FORCEPROP 2 LASTPROP $XRERR UNIQUE?
J 0
(-1315 -1150);
DISPLAY 0.638298 (-1315 -1150);
PAINT MONO (-1315 -1150);
DISPLAY INVISIBLE (-1315 -1150);
WIRE 16 -1 (300 -100)(700 -100);
FORCEPROP 2 LAST SIG_NAME SW_P3V3_AUX_BOOT
J 0
(190 -140);
DISPLAY 0.617021 (190 -140);
FORCEPROP 2 LASTPROP $XRERR UNIQUE?
J 0
(-50 -140);
DISPLAY 0.638298 (-50 -140);
PAINT MONO (-50 -140);
DISPLAY INVISIBLE (-50 -140);
WIRE 16 -1 (-550 -1100)(-1075 -1100);
FORCEPROP 2 LAST SIG_NAME NC_PU9_1
J 0
(-1085 -1090);
DISPLAY 0.617021 (-1085 -1090);
FORCEPROP 2 LASTPROP $XRERR UNIQUE?
J 0
(-1315 -1100);
DISPLAY 0.638298 (-1315 -1100);
PAINT MONO (-1315 -1100);
DISPLAY INVISIBLE (-1315 -1100);
WIRE 16 -1 (-550 -650)(-1075 -650);
FORCEPROP 2 LAST SIG_NAME NC_HICCUP
J 0
(-1085 -640);
DISPLAY 0.617021 (-1085 -640);
FORCEPROP 2 LASTPROP $XRERR UNIQUE?
J 0
(-1315 -650);
DISPLAY 0.638298 (-1315 -650);
PAINT MONO (-1315 -650);
DISPLAY INVISIBLE (-1315 -650);
WIRE 16 -1 (-1350 -1075)(-1350 -950);
FORCEPROP 2 LAST SIG_NAME P3V3_AUX_ILIM
J 0
(-1085 -940);
DISPLAY 0.617021 (-1085 -940);
FORCEPROP 2 LASTPROP $XRERR UNIQUE?
J 0
(-1325 -940);
DISPLAY 0.638298 (-1325 -940);
PAINT MONO (-1325 -940);
DISPLAY INVISIBLE (-1325 -940);
WIRE 16 -1 (-1350 -950)(-550 -950);
WIRE 16 -1 (-2800 -500)(-2800 -100);
WIRE 16 -1 (-2800 -100)(-3325 -100);
FORCEPROP 2 LAST SIG_NAME PWRGD_P5V_AUX
J 0
(-3310 -90);
DISPLAY 0.638298 (-3310 -90);
WIRE 16 -1 (1150 -300)(1150 -100);
FORCEPROP 2 LAST SIG_NAME SW_P3V3_AUX_BOOT_R
R 3
J 0
(1165 135);
DISPLAY 0.617021 (1165 135);
FORCEPROP 2 LASTPROP $XRERR UNIQUE?
J 0
(925 135);
DISPLAY 0.638298 (925 135);
PAINT MONO (925 135);
DISPLAY INVISIBLE (925 135);
WIRE 16 -1 (825 -300)(1150 -300);
WIRE 16 -1 (1150 -100)(900 -100);
WIRE 16 -1 (300 -300)(625 -300);
FORCEPROP 2 LAST SIG_NAME SW_P3V3_AUX_BOOTR
J 0
(190 -340);
DISPLAY 0.617021 (190 -340);
FORCEPROP 2 LASTPROP $XRERR UNIQUE?
J 0
(-50 -340);
DISPLAY 0.638298 (-50 -340);
PAINT MONO (-50 -340);
DISPLAY INVISIBLE (-50 -340);
WIRE 16 3135 (4125 2775)(4125 2200);
WIRE 16 3135 (2725 2775)(4125 2775);
WIRE 16 3135 (4125 2200)(2725 2200);
WIRE 16 3135 (2725 2200)(2725 2775);
WIRE 16 -1 (-550 -450)(-1075 -450);
FORCEPROP 2 LAST SIG_NAME NC_PU9_3
J 0
(-1085 -440);
DISPLAY 0.617021 (-1085 -440);
FORCEPROP 2 LASTPROP $XRERR UNIQUE?
J 0
(-1315 -450);
DISPLAY 0.638298 (-1315 -450);
PAINT MONO (-1315 -450);
DISPLAY INVISIBLE (-1315 -450);
WIRE 16 -1 (-550 -500)(-1075 -500);
FORCEPROP 2 LAST SIG_NAME NC_PU9_4
J 0
(-1085 -490);
DISPLAY 0.617021 (-1085 -490);
FORCEPROP 2 LASTPROP $XRERR UNIQUE?
J 0
(-1315 -500);
DISPLAY 0.638298 (-1315 -500);
PAINT MONO (-1315 -500);
DISPLAY INVISIBLE (-1315 -500);
WIRE 16 -1 (-550 -750)(-2150 -750);
FORCEPROP 2 LAST SIG_NAME P3V3_AUX_MODE
J 0
(-1085 -740);
DISPLAY 0.617021 (-1085 -740);
FORCEPROP 2 LASTPROP $XRERR UNIQUE?
J 0
(-1325 -740);
DISPLAY 0.638298 (-1325 -740);
PAINT MONO (-1325 -740);
DISPLAY INVISIBLE (-1325 -740);
WIRE 16 -1 (-2150 -750)(-2150 -875);
WIRE 16 -1 (300 -500)(1325 -500);
FORCEPROP 2 LAST SIG_NAME SW_P3V3_AUX_SW
J 0
(440 -490);
DISPLAY 0.617021 (440 -490);
FORCEPROP 2 LASTPROP $XRERR UNIQUE?
J 0
(200 -490);
DISPLAY 0.638298 (200 -490);
PAINT MONO (200 -490);
DISPLAY INVISIBLE (200 -490);
WIRE 16 -1 (2800 150)(2625 150);
WIRE 16 -1 (2625 25)(2625 150);
WIRE 16 -1 (2625 150)(1525 150);
FORCEPROP 2 LAST SIG_NAME PWRGD_P3V3_AUX
J 0
(1915 160);
DISPLAY 0.617021 (1915 160);
WIRE 16 -1 (300 -700)(1200 -700);
FORCEPROP 2 LAST SIG_NAME P3V3_AUX_FB
J 0
(440 -690);
DISPLAY 0.617021 (440 -690);
FORCEPROP 2 LASTPROP $XRERR UNIQUE?
J 0
(200 -690);
DISPLAY 0.638298 (200 -690);
PAINT MONO (200 -690);
DISPLAY INVISIBLE (200 -690);
WIRE 16 -1 (1200 -1300)(1200 -700);
WIRE 16 -1 (1200 -1300)(1650 -1300);
WIRE 16 -1 (1200 -1375)(1200 -1300);
WIRE 16 -1 (2000 -1300)(1650 -1300);
WIRE 16 -1 (1650 -1600)(1650 -1300);
WIRE 16 -1 (2000 -1600)(1650 -1600);
WIRE 16 2175 (-4450 -2500)(-2850 -2500);
WIRE 16 2175 (-4450 -2500)(-4450 -2925);
WIRE 16 2175 (-2850 -2500)(-2850 -2925);
WIRE 16 2175 (-4450 -2925)(-2850 -2925);
WIRE 16 -1 (-675 -100)(-675 -150);
WIRE 16 -1 (-550 -100)(-675 -100);
WIRE 16 -1 (-675 -150)(-1625 -150);
FORCEPROP 2 LAST SIG_NAME P3V3_AUX_VCC
J 0
(-1085 -140);
DISPLAY 0.617021 (-1085 -140);
FORCEPROP 2 LASTPROP $XRERR UNIQUE?
J 0
(-1325 -140);
DISPLAY 0.638298 (-1325 -140);
PAINT MONO (-1325 -140);
DISPLAY INVISIBLE (-1325 -140);
WIRE 16 -1 (-1700 -150)(-1625 -150);
WIRE 16 -1 (-1625 -150)(-1625 -275);
WIRE 16 -1 (-1225 -300)(-550 -300);
FORCEPROP 2 LAST SIG_NAME P3V3_AUX_EN
J 0
(-1085 -290);
DISPLAY 0.617021 (-1085 -290);
FORCEPROP 2 LASTPROP $XRERR UNIQUE?
J 0
(-1325 -290);
DISPLAY 0.638298 (-1325 -290);
PAINT MONO (-1325 -290);
DISPLAY INVISIBLE (-1325 -290);
WIRE 16 -1 (-1225 -700)(-1225 -300);
WIRE 16 -1 (-2250 -700)(-1225 -700);
WIRE 16 -1 (-2250 -925)(-2250 -700);
WIRE 16 -1 (-2700 -925)(-2250 -925);
WIRE 16 -1 (-2800 -925)(-2700 -925);
WIRE 16 -1 (-2700 -1075)(-2700 -925);
WIRE 16 -1 (-2800 -700)(-2800 -925);
WIRE 16 -1 (-3300 -925)(-2800 -925);
WIRE 16 -1 (-3300 -700)(-3300 -925);
WIRE 16 -1 (-3300 -925)(-3300 -1075);
WIRE 16 -1 (-2050 -275)(-2050 -150);
WIRE 16 -1 (-2050 -150)(-1900 -150);
WIRE 16 -1 (-2050 -150)(-2050 -50);
WIRE 16 -1 (-2050 -50)(-550 -50);
FORCEPROP 2 LAST SIG_NAME P3V3_AUX_VDRV
J 0
(-1085 -40);
DISPLAY 0.617021 (-1085 -40);
FORCEPROP 2 LASTPROP $XRERR UNIQUE?
J 0
(-1325 -40);
DISPLAY 0.638298 (-1325 -40);
PAINT MONO (-1325 -40);
DISPLAY INVISIBLE (-1325 -40);
WIRE 16 -1 (-550 100)(-1375 100);
WIRE 16 -1 (-1375 1300)(-1375 100);
WIRE 16 -1 (-1375 1300)(-1725 1300);
WIRE 16 -1 (-1725 1300)(-1725 1200);
WIRE 16 -1 (-1725 1300)(-2050 1300);
WIRE 16 -1 (-2050 1300)(-2050 1200);
WIRE 16 -1 (-2375 1300)(-2050 1300);
WIRE 16 -1 (-2375 1200)(-2375 1300);
WIRE 16 -1 (-2700 1300)(-2375 1300);
WIRE 16 -1 (-2700 1300)(-2700 1200);
WIRE 16 -1 (-3025 1300)(-2700 1300);
WIRE 16 -1 (-3025 1300)(-3025 1200);
WIRE 16 -1 (-3350 1300)(-3025 1300);
FORCEPROP 2 LAST SIG_NAME SW_P3V3_AUX_FLT
J 0
(-3110 1300);
DISPLAY 0.617021 (-3110 1300);
FORCEPROP 2 LASTPROP $XRERR UNIQUE?
J 0
(-3350 1300);
DISPLAY 0.638298 (-3350 1300);
PAINT MONO (-3350 1300);
DISPLAY INVISIBLE (-3350 1300);
WIRE 16 -1 (-3350 1300)(-3350 1200);
WIRE 16 -1 (-3675 1300)(-3350 1300);
WIRE 16 -1 (-3675 1200)(-3675 1300);
WIRE 16 -1 (-3975 1300)(-3675 1300);
WIRE 16 -1 (-3975 1300)(-4050 1300);
WIRE 16 -1 (-3975 1200)(-3975 1300);
WIRE 16 -1 (-4050 1300)(-4050 625);
WIRE 16 -1 (-4050 1300)(-4200 1300);
WIRE 16 -1 (-4050 625)(-3725 625);
WIRE 16 -1 (-4050 550)(-4050 625);
WIRE 16 -1 (-3725 625)(-3400 625);
WIRE 16 -1 (-3725 625)(-3725 550);
WIRE 16 -1 (-3400 625)(-3075 625);
WIRE 16 -1 (-3400 625)(-3400 550);
WIRE 16 -1 (-3075 625)(-2750 625);
WIRE 16 -1 (-3075 625)(-3075 550);
WIRE 16 -1 (-2750 625)(-2425 625);
WIRE 16 -1 (-2750 625)(-2750 550);
WIRE 16 -1 (-2425 625)(-2100 625);
WIRE 16 -1 (-2425 625)(-2425 550);
WIRE 16 -1 (-2100 625)(-1825 625);
WIRE 16 -1 (-2100 625)(-2100 550);
WIRE 16 -1 (-1825 625)(-1625 625);
WIRE 16 -1 (-1825 625)(-1825 525);
WIRE 16 -1 (-1625 625)(-1625 550);
WIRE 16 2175 (-2800 50)(-1425 50);
WIRE 16 2175 (-2800 675)(-2800 50);
WIRE 16 2175 (-1425 675)(-1425 50);
WIRE 16 2175 (-2800 675)(-1425 675);
WIRE 16 -1 (2200 -1600)(2550 -1600);
WIRE 16 -1 (2550 -1600)(2550 -1300);
WIRE 16 -1 (2550 -1300)(4175 -1300);
WIRE 16 -1 (2200 -1300)(2550 -1300);
WIRE 16 -1 (4175 -500)(4175 -1300);
WIRE 16 -1 (3725 -500)(4175 -500);
WIRE 16 -1 (4175 -500)(4175 -250);
WIRE 16 -1 (3725 -625)(3725 -500);
WIRE 16 -1 (3725 -500)(3325 -500);
WIRE 16 -1 (3325 -625)(3325 -500);
WIRE 16 -1 (3325 -500)(2950 -500);
WIRE 16 -1 (2950 -625)(2950 -500);
WIRE 16 -1 (2950 -500)(2550 -500);
WIRE 16 -1 (2100 -500)(2550 -500);
WIRE 16 -1 (2550 -600)(2550 -500);
WIRE 16 -1 (2100 -625)(2100 -500);
WIRE 16 -1 (2100 -500)(1650 -500);
WIRE 16 -1 (1650 -625)(1650 -500);
WIRE 16 -1 (1525 -500)(1650 -500);
WIRE 16 -1 (2950 -1000)(2550 -1000);
WIRE 16 -1 (3325 -1000)(2950 -1000);
WIRE 16 -1 (2950 -825)(2950 -1000);
WIRE 16 -1 (2550 -800)(2550 -1000);
WIRE 16 -1 (2550 -1000)(2100 -1000);
WIRE 16 -1 (2100 -825)(2100 -1000);
WIRE 16 -1 (2100 -1000)(1650 -1000);
WIRE 16 -1 (3725 -1000)(3325 -1000);
WIRE 16 -1 (3325 -825)(3325 -1000);
WIRE 16 -1 (3725 -1000)(3725 -825);
WIRE 16 -1 (3725 -1050)(3725 -1000);
WIRE 16 -1 (1650 -1000)(1650 -825);
WIRE 16 -1 (300 -1100)(350 -1100);
WIRE 16 -1 (350 -1100)(350 -1150);
WIRE 16 -1 (300 -1150)(350 -1150);
WIRE 16 -1 (350 -1150)(350 -1200);
WIRE 16 -1 (-900 925)(-900 825);
WIRE 16 -1 (-1150 925)(-900 925);
WIRE 16 -1 (-1150 1000)(-1150 925);
WIRE 16 -1 (-1150 925)(-1150 150);
WIRE 16 -1 (-1150 150)(-550 150);
WIRE 16 -1 (-3725 200)(-3400 200);
WIRE 16 -1 (-3725 200)(-3725 350);
WIRE 16 -1 (-4050 200)(-3725 200);
WIRE 16 -1 (-3400 200)(-3075 200);
WIRE 16 -1 (-3400 200)(-3400 350);
WIRE 16 -1 (-3075 200)(-2750 200);
WIRE 16 -1 (-3075 350)(-3075 200);
WIRE 16 -1 (-4050 200)(-4050 350);
WIRE 16 -1 (-4050 200)(-4050 150);
WIRE 16 -1 (-2750 200)(-2425 200);
WIRE 16 -1 (-2750 200)(-2750 350);
WIRE 16 -1 (-2425 200)(-2100 200);
WIRE 16 -1 (-2425 200)(-2425 350);
WIRE 16 -1 (-1825 200)(-2100 200);
WIRE 16 -1 (-2100 350)(-2100 200);
WIRE 16 -1 (-1625 200)(-1825 200);
WIRE 16 -1 (-1825 325)(-1825 200);
WIRE 16 -1 (-1625 350)(-1625 200);
WIRE 16 -1 (-3975 850)(-3675 850);
WIRE 16 -1 (-3975 850)(-3975 1000);
WIRE 16 -1 (-3975 775)(-3975 850);
WIRE 16 -1 (-3675 850)(-3350 850);
WIRE 16 -1 (-3675 850)(-3675 1000);
WIRE 16 -1 (-3350 850)(-3025 850);
WIRE 16 -1 (-3350 850)(-3350 1000);
WIRE 16 -1 (-3025 850)(-2700 850);
WIRE 16 -1 (-3025 850)(-3025 1000);
WIRE 16 -1 (-2700 850)(-2375 850);
WIRE 16 -1 (-2700 850)(-2700 1000);
WIRE 16 -1 (-2375 850)(-2050 850);
WIRE 16 -1 (-2375 1000)(-2375 850);
WIRE 16 -1 (-1725 850)(-2050 850);
WIRE 16 -1 (-2050 1000)(-2050 850);
WIRE 16 -1 (-1725 1000)(-1725 850);
DOT 1 (3325 -500);
DOT 1 (2625 150);
DOT 1 (-3300 -925);
DOT 1 (-1625 -150);
DOT 1 (-4525 1300);
DOT 1 (-4050 200);
DOT 1 (-3725 200);
DOT 1 (-3725 625);
DOT 1 (-3975 850);
DOT 1 (-3675 850);
DOT 1 (-3400 200);
DOT 1 (-4050 1300);
DOT 1 (-3975 1300);
DOT 1 (-3675 1300);
DOT 1 (-3350 1300);
DOT 1 (-3075 200);
DOT 1 (-2750 200);
DOT 1 (-2750 625);
DOT 1 (-3025 850);
DOT 1 (-2700 850);
DOT 1 (-2425 200);
DOT 1 (-2425 625);
DOT 1 (-2375 850);
DOT 1 (-3025 1300);
DOT 1 (-2700 1300);
DOT 1 (-2375 1300);
DOT 1 (-1150 925);
DOT 1 (-2050 1300);
DOT 1 (-1725 1300);
DOT 1 (350 -1150);
DOT 1 (900 150);
DOT 1 (1200 -1300);
DOT 1 (1650 -1300);
DOT 1 (1650 -500);
DOT 1 (2100 -1000);
DOT 1 (2550 -1000);
DOT 1 (2550 -1300);
DOT 1 (2950 -1000);
DOT 1 (2100 -500);
DOT 1 (2950 -500);
DOT 1 (3325 -1000);
DOT 1 (3725 -1000);
DOT 1 (3725 -500);
DOT 1 (4175 -500);
DOT 1 (-2050 -150);
DOT 1 (-4050 625);
DOT 1 (-3350 850);
DOT 1 (-3075 625);
DOT 1 (-2800 -925);
DOT 1 (-2700 -925);
DOT 1 (-2050 850);
DOT 1 (2550 -500);
DOT 1 (-3400 625);
DOT 1 (-2100 200);
DOT 1 (-2100 625);
DOT 1 (-1825 625);
DOT 1 (-1825 200);
FORCENOTE
BOM NOTE
(-4425 -2200) 0;
DISPLAY LEFT (-4425 -2200);
DISPLAY 1.170213 (-4425 -2200);
PAINT WHITE (-4425 -2200);
FORCENOTE
1ST AL003284002/NCP3284AMNTXG/ONSEMI
(-4425 -2275) 0;
DISPLAY LEFT (-4425 -2275);
DISPLAY 1.021277 (-4425 -2275);
PAINT WHITE (-4425 -2275);
FORCENOTE
2ND AL003889000/IR3889MTRPBF/INFINEON
(-4425 -2350) 0;
DISPLAY LEFT (-4425 -2350);
DISPLAY 1.021277 (-4425 -2350);
PAINT WHITE (-4425 -2350);
FORCENOTE
TSS=4MS
(-2075 -1425) 0;
DISPLAY LEFT (-2075 -1425);
DISPLAY 1.595745 (-2075 -1425);
PAINT WHITE (-2075 -1425);
FORCENOTE
ESR=9.5M OHM
(-3925 875) 0;
DISPLAY LEFT (-3925 875);
DISPLAY 0.404255 (-3925 875);
FORCENOTE
P3V3_AUX
(-1350 2450) 0;
DISPLAY LEFT (-1350 2450);
DISPLAY 4.914894 (-1350 2450);
PAINT YELLOW (-1350 2450);
FORCENOTE
RB
(1000 -1525) 0;
DISPLAY LEFT (1000 -1525);
DISPLAY 1.021277 (1000 -1525);
FORCENOTE
RA
(1700 -1250) 0;
DISPLAY LEFT (1700 -1250);
DISPLAY 1.021277 (1700 -1250);
FORCENOTE
VO=0.8(1+RA/RB)=3.3V
(2800 -1575) 0;
DISPLAY LEFT (2800 -1575);
DISPLAY 1.021277 (2800 -1575);
PAINT SKYBLUE (2800 -1575);
FORCENOTE
WORK FREQUENCY = 600KHZ
(2750 2225) 0;
DISPLAY LEFT (2750 2225);
DISPLAY 1.021277 (2750 2225);
PAINT WHITE (2750 2225);
FORCENOTE
CURRENT STEP = 10.5A
(2750 2275) 0;
DISPLAY LEFT (2750 2275);
DISPLAY 1.021277 (2750 2275);
PAINT WHITE (2750 2275);
FORCENOTE
ESR=9.5M OHM
(-3625 875) 0;
DISPLAY LEFT (-3625 875);
DISPLAY 0.404255 (-3625 875);
FORCENOTE
DESIGN SPECIFICATION
(2750 2700) 0;
DISPLAY LEFT (2750 2700);
DISPLAY 1.021277 (2750 2700);
PAINT WHITE (2750 2700);
FORCENOTE
OUTPUT VOLTAGE = 3.3V+/-5%
(2750 2625) 0;
DISPLAY LEFT (2750 2625);
DISPLAY 1.021277 (2750 2625);
PAINT WHITE (2750 2625);
FORCENOTE
OUTPUT RIPPLE & NOISE < 50MV
(2750 2575) 0;
DISPLAY LEFT (2750 2575);
DISPLAY 1.021277 (2750 2575);
PAINT WHITE (2750 2575);
FORCENOTE
TDC = 19A
(2750 2475) 0;
DISPLAY LEFT (2750 2475);
DISPLAY 1.021277 (2750 2475);
PAINT RED (2750 2475);
FORCENOTE
TRANSIENT TOLERANCE = 330MV
(2750 2525) 0;
DISPLAY LEFT (2750 2525);
DISPLAY 1.021277 (2750 2525);
PAINT WHITE (2750 2525);
FORCENOTE
IMAX = 21A
(2750 2425) 0;
DISPLAY LEFT (2750 2425);
DISPLAY 1.021277 (2750 2425);
PAINT RED (2750 2425);
FORCENOTE
OCP = 32A
(2750 2375) 0;
DISPLAY LEFT (2750 2375);
DISPLAY 1.021277 (2750 2375);
PAINT RED (2750 2375);
FORCENOTE
SLEW RATE = 2.5A/US
(2750 2325) 0;
DISPLAY LEFT (2750 2325);
DISPLAY 1.021277 (2750 2325);
PAINT WHITE (2750 2325);
FORCENOTE
ISAT=53A@100C
(1650 -225) 0;
DISPLAY LEFT (1650 -225);
DISPLAY 1.021277 (1650 -225);
FORCENOTE
DCR=1.5M OHM
(1650 -300) 0;
DISPLAY LEFT (1650 -300);
DISPLAY 1.021277 (1650 -300);
FORCENOTE
14.3*12.9*8.0
(1650 -150) 0;
DISPLAY LEFT (1650 -150);
DISPLAY 1.021277 (1650 -150);
FORCENOTE
 EM-15AM17VG1-QS
(1600 -75) 0;
DISPLAY LEFT (1600 -75);
DISPLAY 1.021277 (1600 -75);
FORCENOTE
1ST 
(-4425 -2675) 0;
DISPLAY LEFT (-4425 -2675);
DISPLAY 1.170213 (-4425 -2675);
PAINT WHITE (-4425 -2675);
FORCENOTE
PC8008 CHANGE TO CH5473KE902
(-4200 -2900) 0;
DISPLAY LEFT (-4200 -2900);
DISPLAY 1.021277 (-4200 -2900);
PAINT WHITE (-4200 -2900);
FORCENOTE
PC569  CHANGE TO CH12206JB00
(-4200 -2825) 0;
DISPLAY LEFT (-4200 -2825);
DISPLAY 1.021277 (-4200 -2825);
PAINT WHITE (-4200 -2825);
FORCENOTE
2ND PR836 EMPTY 
(-4425 -2750) 0;
DISPLAY LEFT (-4425 -2750);
DISPLAY 1.170213 (-4425 -2750);
PAINT WHITE (-4425 -2750);
FORCENOTE
BOM CHANGE R&C TABLE
(-4425 -2600) 0;
DISPLAY LEFT (-4425 -2600);
DISPLAY 1.170213 (-4425 -2600);
PAINT WHITE (-4425 -2600);
FORCENOTE
BASE ON POC
(-2750 150) 0;
DISPLAY LEFT (-2750 150);
DISPLAY 1.021277 (-2750 150);
FORCENOTE
TO IMPROVE INPUT RIPPLE
(-2750 75) 0;
DISPLAY LEFT (-2750 75);
DISPLAY 1.021277 (-2750 75);
QUIT
